FILE_TYPE = MACRO_DRAWING;
SET COLOR_WIRE YELLOW;
SET COLOR_PROP ORANGE;
SET COLOR_DOT WHITE;
SET COLOR_ARC YELLOW;
SET COLOR_BODY GREEN;
SET COLOR_NOTE PURPLE;
SET PROP_DISPLAY VALUE;
SET PAGE_NUMBER P319;
FORCEADD OFFPAGE..1
(-3375 -1075);
FORCEPROP 2 LAST $XR0 176 
J 0
(-3627 -1075);
DISPLAY 0.638298 (-3627 -1075);
PAINT MONO (-3627 -1075);
FORCEPROP 2 LAST PATH I1
J 0
(-3625 -1025);
DISPLAY 1.021277 (-3625 -1025);
DISPLAY INVISIBLE (-3625 -1025);
FORCEPROP 1 LAST OFFPAGE TRUE
J 0
(-3050 -1200);
DISPLAY 0.872340 (-3050 -1200);
PAINT AQUA (-3050 -1200);
DISPLAY INVISIBLE (-3050 -1200);
FORCEPROP 1 LAST COMMENT_BODY TRUE
J 0
(-3250 -1175);
DISPLAY 0.872340 (-3250 -1175);
PAINT GREEN (-3250 -1175);
DISPLAY INVISIBLE (-3250 -1175);
FORCEPROP 2 LAST CDS_LIB standard
J 0
(-3375 -1075);
DISPLAY INVISIBLE (-3375 -1075);
FORCEADD OFFPAGE..1
(-3375 -225);
FORCEPROP 2 LAST $XR0 176 
J 0
(-3627 -225);
DISPLAY 0.638298 (-3627 -225);
PAINT MONO (-3627 -225);
FORCEPROP 2 LAST PATH I11
J 0
(-3625 -175);
DISPLAY 1.021277 (-3625 -175);
DISPLAY INVISIBLE (-3625 -175);
FORCEPROP 1 LAST OFFPAGE TRUE
J 0
(-3050 -350);
DISPLAY 0.872340 (-3050 -350);
PAINT AQUA (-3050 -350);
DISPLAY INVISIBLE (-3050 -350);
FORCEPROP 1 LAST COMMENT_BODY TRUE
J 0
(-3250 -325);
DISPLAY 0.872340 (-3250 -325);
PAINT GREEN (-3250 -325);
DISPLAY INVISIBLE (-3250 -325);
FORCEPROP 2 LAST CDS_LIB standard
J 0
(-3375 -225);
DISPLAY INVISIBLE (-3375 -225);
FORCEADD OFFPAGE..1
(-3375 -175);
FORCEPROP 2 LAST $XR0 176 
J 0
(-3627 -175);
DISPLAY 0.638298 (-3627 -175);
PAINT MONO (-3627 -175);
FORCEPROP 2 LAST PATH I12
J 0
(-3625 -125);
DISPLAY 1.021277 (-3625 -125);
DISPLAY INVISIBLE (-3625 -125);
FORCEPROP 1 LAST OFFPAGE TRUE
J 0
(-3050 -300);
DISPLAY 0.872340 (-3050 -300);
PAINT AQUA (-3050 -300);
DISPLAY INVISIBLE (-3050 -300);
FORCEPROP 1 LAST COMMENT_BODY TRUE
J 0
(-3250 -275);
DISPLAY 0.872340 (-3250 -275);
PAINT GREEN (-3250 -275);
DISPLAY INVISIBLE (-3250 -275);
FORCEPROP 2 LAST CDS_LIB standard
J 0
(-3375 -175);
DISPLAY INVISIBLE (-3375 -175);
FORCEADD OFFPAGE..1
(-3375 -75);
FORCEPROP 2 LAST $XR0 177 
J 0
(-3627 -75);
DISPLAY 0.638298 (-3627 -75);
PAINT MONO (-3627 -75);
FORCEPROP 2 LAST PATH I13
J 0
(-3625 -25);
DISPLAY 1.021277 (-3625 -25);
DISPLAY INVISIBLE (-3625 -25);
FORCEPROP 1 LAST COMMENT_BODY TRUE
J 0
(-3250 -175);
DISPLAY 0.872340 (-3250 -175);
PAINT GREEN (-3250 -175);
DISPLAY INVISIBLE (-3250 -175);
FORCEPROP 1 LAST OFFPAGE TRUE
J 0
(-3050 -200);
DISPLAY 0.872340 (-3050 -200);
PAINT AQUA (-3050 -200);
DISPLAY INVISIBLE (-3050 -200);
FORCEPROP 2 LAST CDS_LIB standard
J 0
(-3375 -75);
DISPLAY INVISIBLE (-3375 -75);
FORCEADD OFFPAGE..1
(-3375 -25);
FORCEPROP 2 LAST $XR0 177 
J 0
(-3627 -25);
DISPLAY 0.638298 (-3627 -25);
PAINT MONO (-3627 -25);
FORCEPROP 2 LAST PATH I14
J 0
(-3625 25);
DISPLAY 1.021277 (-3625 25);
DISPLAY INVISIBLE (-3625 25);
FORCEPROP 1 LAST COMMENT_BODY TRUE
J 0
(-3250 -125);
DISPLAY 0.872340 (-3250 -125);
PAINT GREEN (-3250 -125);
DISPLAY INVISIBLE (-3250 -125);
FORCEPROP 1 LAST OFFPAGE TRUE
J 0
(-3050 -150);
DISPLAY 0.872340 (-3050 -150);
PAINT AQUA (-3050 -150);
DISPLAY INVISIBLE (-3050 -150);
FORCEPROP 2 LAST CDS_LIB standard
J 0
(-3375 -25);
DISPLAY INVISIBLE (-3375 -25);
FORCEADD UNIVERSAL_GND..1
(-2275 -1475);
FORCEPROP 3 LASTPIN (-2275 -1425) SIG_NAME GND\g
J 0
(-2265 -1415);
DISPLAY 0.659574 (-2265 -1415);
PAINT MONO (-2265 -1415);
DISPLAY INVISIBLE (-2265 -1415);
FORCEPROP 1 LAST PATH I15
J 0
(-2200 -1475);
DISPLAY 0.872340 (-2200 -1475);
PAINT AQUA (-2200 -1475);
DISPLAY INVISIBLE (-2200 -1475);
FORCEPROP 1 LAST HDL_POWER GND
J 1
(-2250 -1550);
DISPLAY 0.872340 (-2250 -1550);
PAINT GREEN (-2250 -1550);
DISPLAY INVISIBLE (-2250 -1550);
FORCEPROP 2 LAST CDS_LIB logical_power
J 0
(-2275 -1475);
DISPLAY INVISIBLE (-2275 -1475);
FORCEADD OFFPAGE..2
R 2
(-3375 125);
FORCEPROP 2 LAST $XR0 61 
J 0
(-3629 125);
DISPLAY 0.638298 (-3629 125);
PAINT MONO (-3629 125);
FORCEPROP 2 LAST PATH I16
J 0
(-3625 175);
DISPLAY 1.021277 (-3625 175);
DISPLAY INVISIBLE (-3625 175);
FORCEPROP 1 LAST OFFPAGE TRUE
J 2
(-3700 0);
DISPLAY 0.872340 (-3700 0);
PAINT AQUA (-3700 0);
DISPLAY INVISIBLE (-3700 0);
FORCEPROP 1 LAST COMMENT_BODY TRUE
J 2
(-3330 30);
DISPLAY 0.872340 (-3330 30);
PAINT GREEN (-3330 30);
DISPLAY INVISIBLE (-3330 30);
FORCEPROP 2 LAST CDS_LIB standard
J 0
(-3375 125);
DISPLAY INVISIBLE (-3375 125);
FORCEADD OFFPAGE..5
(-3375 75);
FORCEPROP 2 LAST $XR0 61 
J 0
(-3629 75);
DISPLAY 0.638298 (-3629 75);
PAINT MONO (-3629 75);
FORCEPROP 2 LAST PATH I17
J 0
(-3625 125);
DISPLAY 1.021277 (-3625 125);
DISPLAY INVISIBLE (-3625 125);
FORCEPROP 1 LAST OFFPAGE TRUE
J 0
(-3050 -50);
DISPLAY 0.872340 (-3050 -50);
PAINT AQUA (-3050 -50);
DISPLAY INVISIBLE (-3050 -50);
FORCEPROP 1 LAST COMMENT_BODY TRUE
J 0
(-3275 0);
DISPLAY 1.170213 (-3275 0);
PAINT GREEN (-3275 0);
DISPLAY INVISIBLE (-3275 0);
FORCEPROP 2 LAST CDS_LIB standard
J 0
(-3375 75);
DISPLAY INVISIBLE (-3375 75);
FORCEADD OFFPAGE..5
(-3375 225);
FORCEPROP 2 LAST $XR0 61 
J 0
(-3629 225);
DISPLAY 0.638298 (-3629 225);
PAINT MONO (-3629 225);
FORCEPROP 2 LAST PATH I18
J 0
(-3625 275);
DISPLAY 1.021277 (-3625 275);
DISPLAY INVISIBLE (-3625 275);
FORCEPROP 1 LAST OFFPAGE TRUE
J 0
(-3050 100);
DISPLAY 0.872340 (-3050 100);
PAINT AQUA (-3050 100);
DISPLAY INVISIBLE (-3050 100);
FORCEPROP 1 LAST COMMENT_BODY TRUE
J 0
(-3275 150);
DISPLAY 1.170213 (-3275 150);
PAINT GREEN (-3275 150);
DISPLAY INVISIBLE (-3275 150);
FORCEPROP 2 LAST CDS_LIB standard
J 0
(-3375 225);
DISPLAY INVISIBLE (-3375 225);
FORCEADD OFFPAGE..2
R 2
(-3375 275);
FORCEPROP 2 LAST $XR0 61 
J 0
(-3629 275);
DISPLAY 0.638298 (-3629 275);
PAINT MONO (-3629 275);
FORCEPROP 2 LAST PATH I19
J 0
(-3625 325);
DISPLAY 1.021277 (-3625 325);
DISPLAY INVISIBLE (-3625 325);
FORCEPROP 1 LAST OFFPAGE TRUE
J 2
(-3700 150);
DISPLAY 0.872340 (-3700 150);
PAINT AQUA (-3700 150);
DISPLAY INVISIBLE (-3700 150);
FORCEPROP 1 LAST COMMENT_BODY TRUE
J 2
(-3330 180);
DISPLAY 0.872340 (-3330 180);
PAINT GREEN (-3330 180);
DISPLAY INVISIBLE (-3330 180);
FORCEPROP 2 LAST CDS_LIB standard
J 0
(-3375 275);
DISPLAY INVISIBLE (-3375 275);
FORCEADD OFFPAGE..1
(-3375 -1025);
FORCEPROP 2 LAST $XR0 176 
J 0
(-3627 -1025);
DISPLAY 0.638298 (-3627 -1025);
PAINT MONO (-3627 -1025);
FORCEPROP 2 LAST PATH I2
J 0
(-3625 -975);
DISPLAY 1.021277 (-3625 -975);
DISPLAY INVISIBLE (-3625 -975);
FORCEPROP 1 LAST OFFPAGE TRUE
J 0
(-3050 -1150);
DISPLAY 0.872340 (-3050 -1150);
PAINT AQUA (-3050 -1150);
DISPLAY INVISIBLE (-3050 -1150);
FORCEPROP 1 LAST COMMENT_BODY TRUE
J 0
(-3250 -1125);
DISPLAY 0.872340 (-3250 -1125);
PAINT GREEN (-3250 -1125);
DISPLAY INVISIBLE (-3250 -1125);
FORCEPROP 2 LAST CDS_LIB standard
J 0
(-3375 -1025);
DISPLAY INVISIBLE (-3375 -1025);
FORCEADD OFFPAGE..1
(-3375 525);
FORCEPROP 2 LAST $XR0 176 
J 0
(-3627 525);
DISPLAY 0.638298 (-3627 525);
PAINT MONO (-3627 525);
FORCEPROP 2 LAST PATH I20
J 0
(-3625 575);
DISPLAY 1.021277 (-3625 575);
DISPLAY INVISIBLE (-3625 575);
FORCEPROP 1 LAST COMMENT_BODY TRUE
J 0
(-3250 425);
DISPLAY 0.872340 (-3250 425);
PAINT GREEN (-3250 425);
DISPLAY INVISIBLE (-3250 425);
FORCEPROP 1 LAST OFFPAGE TRUE
J 0
(-3050 400);
DISPLAY 0.872340 (-3050 400);
PAINT AQUA (-3050 400);
DISPLAY INVISIBLE (-3050 400);
FORCEPROP 2 LAST CDS_LIB standard
J 0
(-3375 525);
DISPLAY INVISIBLE (-3375 525);
FORCEADD OFFPAGE..1
(-3375 725);
FORCEPROP 2 LAST $XR0 177 
J 0
(-3627 725);
DISPLAY 0.638298 (-3627 725);
PAINT MONO (-3627 725);
FORCEPROP 2 LAST PATH I21
J 0
(-3625 775);
DISPLAY 1.021277 (-3625 775);
DISPLAY INVISIBLE (-3625 775);
FORCEPROP 1 LAST OFFPAGE TRUE
J 0
(-3050 600);
DISPLAY 0.872340 (-3050 600);
PAINT AQUA (-3050 600);
DISPLAY INVISIBLE (-3050 600);
FORCEPROP 1 LAST COMMENT_BODY TRUE
J 0
(-3250 625);
DISPLAY 0.872340 (-3250 625);
PAINT GREEN (-3250 625);
DISPLAY INVISIBLE (-3250 625);
FORCEPROP 2 LAST CDS_LIB standard
J 0
(-3375 725);
DISPLAY INVISIBLE (-3375 725);
FORCEADD OFFPAGE..1
(-3375 675);
FORCEPROP 2 LAST $XR0 177 
J 0
(-3627 675);
DISPLAY 0.638298 (-3627 675);
PAINT MONO (-3627 675);
FORCEPROP 2 LAST PATH I22
J 0
(-3625 725);
DISPLAY 1.021277 (-3625 725);
DISPLAY INVISIBLE (-3625 725);
FORCEPROP 1 LAST COMMENT_BODY TRUE
J 0
(-3250 575);
DISPLAY 0.872340 (-3250 575);
PAINT GREEN (-3250 575);
DISPLAY INVISIBLE (-3250 575);
FORCEPROP 1 LAST OFFPAGE TRUE
J 0
(-3050 550);
DISPLAY 0.872340 (-3050 550);
PAINT AQUA (-3050 550);
DISPLAY INVISIBLE (-3050 550);
FORCEPROP 2 LAST CDS_LIB standard
J 0
(-3375 675);
DISPLAY INVISIBLE (-3375 675);
FORCEADD OFFPAGE..1
(-3375 575);
FORCEPROP 2 LAST $XR0 176 
J 0
(-3627 575);
DISPLAY 0.638298 (-3627 575);
PAINT MONO (-3627 575);
FORCEPROP 2 LAST PATH I23
J 0
(-3625 625);
DISPLAY 1.021277 (-3625 625);
DISPLAY INVISIBLE (-3625 625);
FORCEPROP 1 LAST OFFPAGE TRUE
J 0
(-3050 450);
DISPLAY 0.872340 (-3050 450);
PAINT AQUA (-3050 450);
DISPLAY INVISIBLE (-3050 450);
FORCEPROP 1 LAST COMMENT_BODY TRUE
J 0
(-3250 475);
DISPLAY 0.872340 (-3250 475);
PAINT GREEN (-3250 475);
DISPLAY INVISIBLE (-3250 475);
FORCEPROP 2 LAST CDS_LIB standard
J 0
(-3375 575);
DISPLAY INVISIBLE (-3375 575);
FORCEADD OFFPAGE..5
(-3375 825);
FORCEPROP 2 LAST $XR0 61 
J 0
(-3629 825);
DISPLAY 0.638298 (-3629 825);
PAINT MONO (-3629 825);
FORCEPROP 2 LAST PATH I24
J 0
(-3625 875);
DISPLAY 1.021277 (-3625 875);
DISPLAY INVISIBLE (-3625 875);
FORCEPROP 1 LAST COMMENT_BODY TRUE
J 0
(-3275 750);
DISPLAY 1.170213 (-3275 750);
PAINT GREEN (-3275 750);
DISPLAY INVISIBLE (-3275 750);
FORCEPROP 1 LAST OFFPAGE TRUE
J 0
(-3050 700);
DISPLAY 0.872340 (-3050 700);
PAINT AQUA (-3050 700);
DISPLAY INVISIBLE (-3050 700);
FORCEPROP 2 LAST CDS_LIB standard
J 0
(-3375 825);
DISPLAY INVISIBLE (-3375 825);
FORCEADD OFFPAGE..2
R 2
(-3375 875);
FORCEPROP 2 LAST $XR0 61 
J 0
(-3629 875);
DISPLAY 0.638298 (-3629 875);
PAINT MONO (-3629 875);
FORCEPROP 2 LAST PATH I25
J 0
(-3625 925);
DISPLAY 1.021277 (-3625 925);
DISPLAY INVISIBLE (-3625 925);
FORCEPROP 1 LAST COMMENT_BODY TRUE
J 2
(-3330 780);
DISPLAY 0.872340 (-3330 780);
PAINT GREEN (-3330 780);
DISPLAY INVISIBLE (-3330 780);
FORCEPROP 1 LAST OFFPAGE TRUE
J 2
(-3700 750);
DISPLAY 0.872340 (-3700 750);
PAINT AQUA (-3700 750);
DISPLAY INVISIBLE (-3700 750);
FORCEPROP 2 LAST CDS_LIB standard
J 0
(-3375 875);
DISPLAY INVISIBLE (-3375 875);
FORCEADD OFFPAGE..5
(-3375 975);
FORCEPROP 2 LAST $XR0 61 
J 0
(-3629 975);
DISPLAY 0.638298 (-3629 975);
PAINT MONO (-3629 975);
FORCEPROP 2 LAST PATH I26
J 0
(-3625 1025);
DISPLAY 1.021277 (-3625 1025);
DISPLAY INVISIBLE (-3625 1025);
FORCEPROP 1 LAST COMMENT_BODY TRUE
J 0
(-3275 900);
DISPLAY 1.170213 (-3275 900);
PAINT GREEN (-3275 900);
DISPLAY INVISIBLE (-3275 900);
FORCEPROP 1 LAST OFFPAGE TRUE
J 0
(-3050 850);
DISPLAY 0.872340 (-3050 850);
PAINT AQUA (-3050 850);
DISPLAY INVISIBLE (-3050 850);
FORCEPROP 2 LAST CDS_LIB standard
J 0
(-3375 975);
DISPLAY INVISIBLE (-3375 975);
FORCEADD OFFPAGE..2
R 2
(-3375 1025);
FORCEPROP 2 LAST $XR0 61 
J 0
(-3629 1025);
DISPLAY 0.638298 (-3629 1025);
PAINT MONO (-3629 1025);
FORCEPROP 2 LAST PATH I27
J 0
(-3625 1075);
DISPLAY 1.021277 (-3625 1075);
DISPLAY INVISIBLE (-3625 1075);
FORCEPROP 1 LAST COMMENT_BODY TRUE
J 2
(-3330 930);
DISPLAY 0.872340 (-3330 930);
PAINT GREEN (-3330 930);
DISPLAY INVISIBLE (-3330 930);
FORCEPROP 1 LAST OFFPAGE TRUE
J 2
(-3700 900);
DISPLAY 0.872340 (-3700 900);
PAINT AQUA (-3700 900);
DISPLAY INVISIBLE (-3700 900);
FORCEPROP 2 LAST CDS_LIB standard
J 0
(-3375 1025);
DISPLAY INVISIBLE (-3375 1025);
FORCEADD OFFPAGE..1
(-3375 -925);
FORCEPROP 2 LAST $XR0 177 
J 0
(-3627 -925);
DISPLAY 0.638298 (-3627 -925);
PAINT MONO (-3627 -925);
FORCEPROP 2 LAST PATH I3
J 0
(-3625 -875);
DISPLAY 1.021277 (-3625 -875);
DISPLAY INVISIBLE (-3625 -875);
FORCEPROP 1 LAST OFFPAGE TRUE
J 0
(-3050 -1050);
DISPLAY 0.872340 (-3050 -1050);
PAINT AQUA (-3050 -1050);
DISPLAY INVISIBLE (-3050 -1050);
FORCEPROP 1 LAST COMMENT_BODY TRUE
J 0
(-3250 -1025);
DISPLAY 0.872340 (-3250 -1025);
PAINT GREEN (-3250 -1025);
DISPLAY INVISIBLE (-3250 -1025);
FORCEPROP 2 LAST CDS_LIB standard
J 0
(-3375 -925);
DISPLAY INVISIBLE (-3375 -925);
FORCEADD OFFPAGE..1
(-3375 1375);
FORCEPROP 2 LAST $XR0 176 
J 0
(-3627 1375);
DISPLAY 0.638298 (-3627 1375);
PAINT MONO (-3627 1375);
FORCEPROP 2 LAST PATH I30
J 0
(-3625 1425);
DISPLAY 1.021277 (-3625 1425);
DISPLAY INVISIBLE (-3625 1425);
FORCEPROP 1 LAST COMMENT_BODY TRUE
J 0
(-3250 1275);
DISPLAY 0.872340 (-3250 1275);
PAINT GREEN (-3250 1275);
DISPLAY INVISIBLE (-3250 1275);
FORCEPROP 1 LAST OFFPAGE TRUE
J 0
(-3050 1250);
DISPLAY 0.872340 (-3050 1250);
PAINT AQUA (-3050 1250);
DISPLAY INVISIBLE (-3050 1250);
FORCEPROP 2 LAST CDS_LIB standard
J 0
(-3375 1375);
DISPLAY INVISIBLE (-3375 1375);
FORCEADD OFFPAGE..1
(-3375 1425);
FORCEPROP 2 LAST $XR0 176 
J 0
(-3627 1425);
DISPLAY 0.638298 (-3627 1425);
PAINT MONO (-3627 1425);
FORCEPROP 2 LAST PATH I31
J 0
(-3625 1475);
DISPLAY 1.021277 (-3625 1475);
DISPLAY INVISIBLE (-3625 1475);
FORCEPROP 1 LAST COMMENT_BODY TRUE
J 0
(-3250 1325);
DISPLAY 0.872340 (-3250 1325);
PAINT GREEN (-3250 1325);
DISPLAY INVISIBLE (-3250 1325);
FORCEPROP 1 LAST OFFPAGE TRUE
J 0
(-3050 1300);
DISPLAY 0.872340 (-3050 1300);
PAINT AQUA (-3050 1300);
DISPLAY INVISIBLE (-3050 1300);
FORCEPROP 2 LAST CDS_LIB standard
J 0
(-3375 1425);
DISPLAY INVISIBLE (-3375 1425);
FORCEADD OFFPAGE..1
(-3375 1525);
FORCEPROP 2 LAST $XR0 177 
J 0
(-3627 1525);
DISPLAY 0.638298 (-3627 1525);
PAINT MONO (-3627 1525);
FORCEPROP 2 LAST PATH I32
J 0
(-3625 1575);
DISPLAY 1.021277 (-3625 1575);
DISPLAY INVISIBLE (-3625 1575);
FORCEPROP 1 LAST OFFPAGE TRUE
J 0
(-3050 1400);
DISPLAY 0.872340 (-3050 1400);
PAINT AQUA (-3050 1400);
DISPLAY INVISIBLE (-3050 1400);
FORCEPROP 1 LAST COMMENT_BODY TRUE
J 0
(-3250 1425);
DISPLAY 0.872340 (-3250 1425);
PAINT GREEN (-3250 1425);
DISPLAY INVISIBLE (-3250 1425);
FORCEPROP 2 LAST CDS_LIB standard
J 0
(-3375 1525);
DISPLAY INVISIBLE (-3375 1525);
FORCEADD OFFPAGE..1
(-3375 1575);
FORCEPROP 2 LAST $XR0 177 
J 0
(-3627 1575);
DISPLAY 0.638298 (-3627 1575);
PAINT MONO (-3627 1575);
FORCEPROP 2 LAST PATH I33
J 0
(-3625 1625);
DISPLAY 1.021277 (-3625 1625);
DISPLAY INVISIBLE (-3625 1625);
FORCEPROP 1 LAST COMMENT_BODY TRUE
J 0
(-3250 1475);
DISPLAY 0.872340 (-3250 1475);
PAINT GREEN (-3250 1475);
DISPLAY INVISIBLE (-3250 1475);
FORCEPROP 1 LAST OFFPAGE TRUE
J 0
(-3050 1450);
DISPLAY 0.872340 (-3050 1450);
PAINT AQUA (-3050 1450);
DISPLAY INVISIBLE (-3050 1450);
FORCEPROP 2 LAST CDS_LIB standard
J 0
(-3375 1575);
DISPLAY INVISIBLE (-3375 1575);
FORCEADD OFFPAGE..5
(-3375 1675);
FORCEPROP 2 LAST $XR0 61 
J 0
(-3629 1675);
DISPLAY 0.638298 (-3629 1675);
PAINT MONO (-3629 1675);
FORCEPROP 2 LAST PATH I34
J 0
(-3625 1725);
DISPLAY 1.021277 (-3625 1725);
DISPLAY INVISIBLE (-3625 1725);
FORCEPROP 1 LAST COMMENT_BODY TRUE
J 0
(-3275 1600);
DISPLAY 1.170213 (-3275 1600);
PAINT GREEN (-3275 1600);
DISPLAY INVISIBLE (-3275 1600);
FORCEPROP 1 LAST OFFPAGE TRUE
J 0
(-3050 1550);
DISPLAY 0.872340 (-3050 1550);
PAINT AQUA (-3050 1550);
DISPLAY INVISIBLE (-3050 1550);
FORCEPROP 2 LAST CDS_LIB standard
J 0
(-3375 1675);
DISPLAY INVISIBLE (-3375 1675);
FORCEADD OFFPAGE..2
R 2
(-3375 1725);
FORCEPROP 2 LAST $XR0 61 
J 0
(-3629 1725);
DISPLAY 0.638298 (-3629 1725);
PAINT MONO (-3629 1725);
FORCEPROP 2 LAST PATH I35
J 0
(-3625 1775);
DISPLAY 1.021277 (-3625 1775);
DISPLAY INVISIBLE (-3625 1775);
FORCEPROP 1 LAST COMMENT_BODY TRUE
J 2
(-3330 1630);
DISPLAY 0.872340 (-3330 1630);
PAINT GREEN (-3330 1630);
DISPLAY INVISIBLE (-3330 1630);
FORCEPROP 1 LAST OFFPAGE TRUE
J 2
(-3700 1600);
DISPLAY 0.872340 (-3700 1600);
PAINT AQUA (-3700 1600);
DISPLAY INVISIBLE (-3700 1600);
FORCEPROP 2 LAST CDS_LIB standard
J 0
(-3375 1725);
DISPLAY INVISIBLE (-3375 1725);
FORCEADD OFFPAGE..5
(-3375 1825);
FORCEPROP 2 LAST $XR0 61 
J 0
(-3629 1825);
DISPLAY 0.638298 (-3629 1825);
PAINT MONO (-3629 1825);
FORCEPROP 2 LAST PATH I36
J 0
(-3625 1875);
DISPLAY 1.021277 (-3625 1875);
DISPLAY INVISIBLE (-3625 1875);
FORCEPROP 1 LAST OFFPAGE TRUE
J 0
(-3050 1700);
DISPLAY 0.872340 (-3050 1700);
PAINT AQUA (-3050 1700);
DISPLAY INVISIBLE (-3050 1700);
FORCEPROP 1 LAST COMMENT_BODY TRUE
J 0
(-3275 1750);
DISPLAY 1.170213 (-3275 1750);
PAINT GREEN (-3275 1750);
DISPLAY INVISIBLE (-3275 1750);
FORCEPROP 2 LAST CDS_LIB standard
J 0
(-3375 1825);
DISPLAY INVISIBLE (-3375 1825);
FORCEADD OFFPAGE..2
R 2
(-3375 1875);
FORCEPROP 2 LAST $XR0 61 
J 0
(-3629 1875);
DISPLAY 0.638298 (-3629 1875);
PAINT MONO (-3629 1875);
FORCEPROP 2 LAST PATH I37
J 0
(-3625 1925);
DISPLAY 1.021277 (-3625 1925);
DISPLAY INVISIBLE (-3625 1925);
FORCEPROP 2 LAST CDS_LIB standard
J 0
(-3375 1875);
DISPLAY INVISIBLE (-3375 1875);
FORCEPROP 1 LAST COMMENT_BODY TRUE
J 2
(-3330 1780);
DISPLAY 0.872340 (-3330 1780);
PAINT GREEN (-3330 1780);
DISPLAY INVISIBLE (-3330 1780);
FORCEPROP 1 LAST OFFPAGE TRUE
J 2
(-3700 1750);
DISPLAY 0.872340 (-3700 1750);
PAINT AQUA (-3700 1750);
DISPLAY INVISIBLE (-3700 1750);
FORCEADD OFFPAGE..1
(1400 -1100);
FORCEPROP 2 LAST $XR0 176 
J 0
(1118 -1100);
DISPLAY 0.638298 (1118 -1100);
PAINT MONO (1118 -1100);
FORCEPROP 2 LAST CDS_LIB standard
J 0
(1400 -1100);
DISPLAY INVISIBLE (1400 -1100);
FORCEPROP 1 LAST COMMENT_BODY TRUE
J 0
(1525 -1200);
DISPLAY 0.872340 (1525 -1200);
PAINT GREEN (1525 -1200);
DISPLAY INVISIBLE (1525 -1200);
FORCEPROP 1 LAST OFFPAGE TRUE
J 0
(1725 -1225);
DISPLAY 0.872340 (1725 -1225);
PAINT AQUA (1725 -1225);
DISPLAY INVISIBLE (1725 -1225);
FORCEPROP 2 LAST PATH I38
J 0
(1125 -1050);
DISPLAY 1.021277 (1125 -1050);
DISPLAY INVISIBLE (1125 -1050);
FORCEADD OFFPAGE..1
(1400 -1150);
FORCEPROP 2 LAST $XR0 176 
J 0
(1118 -1150);
DISPLAY 0.638298 (1118 -1150);
PAINT MONO (1118 -1150);
FORCEPROP 2 LAST CDS_LIB standard
J 0
(1400 -1150);
DISPLAY INVISIBLE (1400 -1150);
FORCEPROP 1 LAST COMMENT_BODY TRUE
J 0
(1525 -1250);
DISPLAY 0.872340 (1525 -1250);
PAINT GREEN (1525 -1250);
DISPLAY INVISIBLE (1525 -1250);
FORCEPROP 1 LAST OFFPAGE TRUE
J 0
(1725 -1275);
DISPLAY 0.872340 (1725 -1275);
PAINT AQUA (1725 -1275);
DISPLAY INVISIBLE (1725 -1275);
FORCEPROP 2 LAST PATH I39
J 0
(1125 -1100);
DISPLAY 1.021277 (1125 -1100);
DISPLAY INVISIBLE (1125 -1100);
FORCEADD OFFPAGE..1
(-3375 -875);
FORCEPROP 2 LAST $XR0 177 
J 0
(-3627 -875);
DISPLAY 0.638298 (-3627 -875);
PAINT MONO (-3627 -875);
FORCEPROP 2 LAST PATH I4
J 0
(-3625 -825);
DISPLAY 1.021277 (-3625 -825);
DISPLAY INVISIBLE (-3625 -825);
FORCEPROP 1 LAST OFFPAGE TRUE
J 0
(-3050 -1000);
DISPLAY 0.872340 (-3050 -1000);
PAINT AQUA (-3050 -1000);
DISPLAY INVISIBLE (-3050 -1000);
FORCEPROP 1 LAST COMMENT_BODY TRUE
J 0
(-3250 -975);
DISPLAY 0.872340 (-3250 -975);
PAINT GREEN (-3250 -975);
DISPLAY INVISIBLE (-3250 -975);
FORCEPROP 2 LAST CDS_LIB standard
J 0
(-3375 -875);
DISPLAY INVISIBLE (-3375 -875);
FORCEADD OFFPAGE..1
(1400 -1000);
FORCEPROP 2 LAST $XR0 177 
J 0
(1118 -1000);
DISPLAY 0.638298 (1118 -1000);
PAINT MONO (1118 -1000);
FORCEPROP 2 LAST CDS_LIB standard
J 0
(1400 -1000);
DISPLAY INVISIBLE (1400 -1000);
FORCEPROP 1 LAST OFFPAGE TRUE
J 0
(1725 -1125);
DISPLAY 0.872340 (1725 -1125);
PAINT AQUA (1725 -1125);
DISPLAY INVISIBLE (1725 -1125);
FORCEPROP 1 LAST COMMENT_BODY TRUE
J 0
(1525 -1100);
DISPLAY 0.872340 (1525 -1100);
PAINT GREEN (1525 -1100);
DISPLAY INVISIBLE (1525 -1100);
FORCEPROP 2 LAST PATH I40
J 0
(1125 -950);
DISPLAY 1.021277 (1125 -950);
DISPLAY INVISIBLE (1125 -950);
FORCEADD OFFPAGE..1
(1400 -950);
FORCEPROP 2 LAST $XR0 177 
J 0
(1118 -950);
DISPLAY 0.638298 (1118 -950);
PAINT MONO (1118 -950);
FORCEPROP 2 LAST CDS_LIB standard
J 0
(1400 -950);
DISPLAY INVISIBLE (1400 -950);
FORCEPROP 1 LAST OFFPAGE TRUE
J 0
(1725 -1075);
DISPLAY 0.872340 (1725 -1075);
PAINT AQUA (1725 -1075);
DISPLAY INVISIBLE (1725 -1075);
FORCEPROP 1 LAST COMMENT_BODY TRUE
J 0
(1525 -1050);
DISPLAY 0.872340 (1525 -1050);
PAINT GREEN (1525 -1050);
DISPLAY INVISIBLE (1525 -1050);
FORCEPROP 2 LAST PATH I41
J 0
(1125 -900);
DISPLAY 1.021277 (1125 -900);
DISPLAY INVISIBLE (1125 -900);
FORCEADD OFFPAGE..5
(1400 -850);
FORCEPROP 2 LAST $XR0 61 
J 0
(1176 -850);
DISPLAY 0.638298 (1176 -850);
PAINT MONO (1176 -850);
FORCEPROP 2 LAST CDS_LIB standard
J 0
(1400 -850);
DISPLAY INVISIBLE (1400 -850);
FORCEPROP 1 LAST COMMENT_BODY TRUE
J 0
(1500 -925);
DISPLAY 1.170213 (1500 -925);
PAINT GREEN (1500 -925);
DISPLAY INVISIBLE (1500 -925);
FORCEPROP 1 LAST OFFPAGE TRUE
J 0
(1725 -975);
DISPLAY 0.872340 (1725 -975);
PAINT AQUA (1725 -975);
DISPLAY INVISIBLE (1725 -975);
FORCEPROP 2 LAST PATH I42
J 0
(1200 -800);
DISPLAY 1.021277 (1200 -800);
DISPLAY INVISIBLE (1200 -800);
FORCEADD OFFPAGE..2
R 2
(1400 -800);
FORCEPROP 2 LAST $XR0 61 
J 0
(1176 -800);
DISPLAY 0.638298 (1176 -800);
PAINT MONO (1176 -800);
FORCEPROP 2 LAST CDS_LIB standard
J 0
(1400 -800);
DISPLAY INVISIBLE (1400 -800);
FORCEPROP 1 LAST COMMENT_BODY TRUE
J 2
(1445 -895);
DISPLAY 0.872340 (1445 -895);
PAINT GREEN (1445 -895);
DISPLAY INVISIBLE (1445 -895);
FORCEPROP 1 LAST OFFPAGE TRUE
J 2
(1075 -925);
DISPLAY 0.872340 (1075 -925);
PAINT AQUA (1075 -925);
DISPLAY INVISIBLE (1075 -925);
FORCEPROP 2 LAST PATH I43
J 0
(1200 -750);
DISPLAY 1.021277 (1200 -750);
DISPLAY INVISIBLE (1200 -750);
FORCEADD OFFPAGE..2
R 2
(1400 -650);
FORCEPROP 2 LAST $XR0 61 
J 0
(1176 -650);
DISPLAY 0.638298 (1176 -650);
PAINT MONO (1176 -650);
FORCEPROP 2 LAST PATH I44
J 0
(1200 -600);
DISPLAY 1.021277 (1200 -600);
DISPLAY INVISIBLE (1200 -600);
FORCEPROP 1 LAST OFFPAGE TRUE
J 2
(1075 -775);
DISPLAY 0.872340 (1075 -775);
PAINT AQUA (1075 -775);
DISPLAY INVISIBLE (1075 -775);
FORCEPROP 1 LAST COMMENT_BODY TRUE
J 2
(1445 -745);
DISPLAY 0.872340 (1445 -745);
PAINT GREEN (1445 -745);
DISPLAY INVISIBLE (1445 -745);
FORCEPROP 2 LAST CDS_LIB standard
J 0
(1400 -650);
DISPLAY INVISIBLE (1400 -650);
FORCEADD OFFPAGE..5
(1400 -700);
FORCEPROP 2 LAST $XR0 61 
J 0
(1176 -700);
DISPLAY 0.638298 (1176 -700);
PAINT MONO (1176 -700);
FORCEPROP 2 LAST CDS_LIB standard
J 0
(1400 -700);
DISPLAY INVISIBLE (1400 -700);
FORCEPROP 1 LAST COMMENT_BODY TRUE
J 0
(1500 -775);
DISPLAY 1.170213 (1500 -775);
PAINT GREEN (1500 -775);
DISPLAY INVISIBLE (1500 -775);
FORCEPROP 1 LAST OFFPAGE TRUE
J 0
(1725 -825);
DISPLAY 0.872340 (1725 -825);
PAINT AQUA (1725 -825);
DISPLAY INVISIBLE (1725 -825);
FORCEPROP 2 LAST PATH I45
J 0
(1200 -650);
DISPLAY 1.021277 (1200 -650);
DISPLAY INVISIBLE (1200 -650);
FORCEADD OFFPAGE..1
(1400 -300);
FORCEPROP 2 LAST $XR0 176 
J 0
(1118 -300);
DISPLAY 0.638298 (1118 -300);
PAINT MONO (1118 -300);
FORCEPROP 2 LAST CDS_LIB standard
J 0
(1400 -300);
DISPLAY INVISIBLE (1400 -300);
FORCEPROP 1 LAST OFFPAGE TRUE
J 0
(1725 -425);
DISPLAY 0.872340 (1725 -425);
PAINT AQUA (1725 -425);
DISPLAY INVISIBLE (1725 -425);
FORCEPROP 1 LAST COMMENT_BODY TRUE
J 0
(1525 -400);
DISPLAY 0.872340 (1525 -400);
PAINT GREEN (1525 -400);
DISPLAY INVISIBLE (1525 -400);
FORCEPROP 2 LAST PATH I47
J 0
(1125 -250);
DISPLAY 1.021277 (1125 -250);
DISPLAY INVISIBLE (1125 -250);
FORCEADD OFFPAGE..1
(1400 -250);
FORCEPROP 2 LAST $XR0 176 
J 0
(1118 -250);
DISPLAY 0.638298 (1118 -250);
PAINT MONO (1118 -250);
FORCEPROP 2 LAST CDS_LIB standard
J 0
(1400 -250);
DISPLAY INVISIBLE (1400 -250);
FORCEPROP 1 LAST OFFPAGE TRUE
J 0
(1725 -375);
DISPLAY 0.872340 (1725 -375);
PAINT AQUA (1725 -375);
DISPLAY INVISIBLE (1725 -375);
FORCEPROP 1 LAST COMMENT_BODY TRUE
J 0
(1525 -350);
DISPLAY 0.872340 (1525 -350);
PAINT GREEN (1525 -350);
DISPLAY INVISIBLE (1525 -350);
FORCEPROP 2 LAST PATH I49
J 0
(1125 -200);
DISPLAY 1.021277 (1125 -200);
DISPLAY INVISIBLE (1125 -200);
FORCEADD OFFPAGE..5
(-3375 -775);
FORCEPROP 2 LAST $XR0 61 
J 0
(-3629 -775);
DISPLAY 0.638298 (-3629 -775);
PAINT MONO (-3629 -775);
FORCEPROP 2 LAST PATH I5
J 0
(-3625 -725);
DISPLAY 1.021277 (-3625 -725);
DISPLAY INVISIBLE (-3625 -725);
FORCEPROP 1 LAST COMMENT_BODY TRUE
J 0
(-3275 -850);
DISPLAY 1.170213 (-3275 -850);
PAINT GREEN (-3275 -850);
DISPLAY INVISIBLE (-3275 -850);
FORCEPROP 1 LAST OFFPAGE TRUE
J 0
(-3050 -900);
DISPLAY 0.872340 (-3050 -900);
PAINT AQUA (-3050 -900);
DISPLAY INVISIBLE (-3050 -900);
FORCEPROP 2 LAST CDS_LIB standard
J 0
(-3375 -775);
DISPLAY INVISIBLE (-3375 -775);
FORCEADD OFFPAGE..1
(1400 -100);
FORCEPROP 2 LAST $XR0 177 
J 0
(1118 -100);
DISPLAY 0.638298 (1118 -100);
PAINT MONO (1118 -100);
FORCEPROP 2 LAST CDS_LIB standard
J 0
(1400 -100);
DISPLAY INVISIBLE (1400 -100);
FORCEPROP 1 LAST COMMENT_BODY TRUE
J 0
(1525 -200);
DISPLAY 0.872340 (1525 -200);
PAINT GREEN (1525 -200);
DISPLAY INVISIBLE (1525 -200);
FORCEPROP 1 LAST OFFPAGE TRUE
J 0
(1725 -225);
DISPLAY 0.872340 (1725 -225);
PAINT AQUA (1725 -225);
DISPLAY INVISIBLE (1725 -225);
FORCEPROP 2 LAST PATH I50
J 0
(1125 -50);
DISPLAY 1.021277 (1125 -50);
DISPLAY INVISIBLE (1125 -50);
FORCEADD OFFPAGE..1
(1400 -150);
FORCEPROP 2 LAST $XR0 177 
J 0
(1118 -150);
DISPLAY 0.638298 (1118 -150);
PAINT MONO (1118 -150);
FORCEPROP 2 LAST CDS_LIB standard
J 0
(1400 -150);
DISPLAY INVISIBLE (1400 -150);
FORCEPROP 1 LAST COMMENT_BODY TRUE
J 0
(1525 -250);
DISPLAY 0.872340 (1525 -250);
PAINT GREEN (1525 -250);
DISPLAY INVISIBLE (1525 -250);
FORCEPROP 1 LAST OFFPAGE TRUE
J 0
(1725 -275);
DISPLAY 0.872340 (1725 -275);
PAINT AQUA (1725 -275);
DISPLAY INVISIBLE (1725 -275);
FORCEPROP 2 LAST PATH I51
J 0
(1125 -100);
DISPLAY 1.021277 (1125 -100);
DISPLAY INVISIBLE (1125 -100);
FORCEADD UNIVERSAL_GND..1
(2450 -1600);
FORCEPROP 3 LASTPIN (2450 -1550) SIG_NAME GND\g
J 0
(2460 -1540);
DISPLAY 0.659574 (2460 -1540);
PAINT MONO (2460 -1540);
DISPLAY INVISIBLE (2460 -1540);
FORCEPROP 2 LAST CDS_LIB logical_power
J 0
(2450 -1600);
DISPLAY INVISIBLE (2450 -1600);
FORCEPROP 1 LAST HDL_POWER GND
J 1
(2475 -1675);
DISPLAY 0.872340 (2475 -1675);
PAINT GREEN (2475 -1675);
DISPLAY INVISIBLE (2475 -1675);
FORCEPROP 1 LAST PATH I52
J 0
(2525 -1600);
DISPLAY 0.872340 (2525 -1600);
PAINT AQUA (2525 -1600);
DISPLAY INVISIBLE (2525 -1600);
FORCEADD CONN112_10137002101LF..2
(3600 350);
FORCEPROP 1 LAST PART_NUMBER DFHSB2FR012
J 0
(2850 2125);
DISPLAY 0.723404 (2850 2125);
PAINT GREEN (2850 2125);
DISPLAY INVISIBLE (2850 2125);
FORCEPROP 2 LAST PART_TYPE THLF
J 0
(2850 2250);
DISPLAY 1.021277 (2850 2250);
FORCEPROP 1 LAST MATERIAL IO
J 0
(2858 2063);
DISPLAY 0.723404 (2858 2063);
PAINT GREEN (2858 2063);
FORCEPROP 1 LAST LOCATION J109
J 0
(2850 2175);
DISPLAY 0.723404 (2850 2175);
PAINT GREEN (2850 2175);
FORCEPROP 0 LASTPIN (2675 -550) $PN A1
J 2
(2665 -540);
DISPLAY 0.680851 (2665 -540);
PAINT MONO (2665 -540);
FORCEPROP 0 LASTPIN (2675 250) $PN A2
J 2
(2665 260);
DISPLAY 0.680851 (2665 260);
PAINT MONO (2665 260);
FORCEPROP 0 LASTPIN (2675 1050) $PN A3
J 2
(2665 1060);
DISPLAY 0.680851 (2665 1060);
PAINT MONO (2665 1060);
FORCEPROP 0 LASTPIN (2675 1850) $PN A4
J 2
(2665 1860);
DISPLAY 0.680851 (2665 1860);
PAINT MONO (2665 1860);
FORCEPROP 0 LASTPIN (2675 -600) $PN B1
J 2
(2665 -590);
DISPLAY 0.680851 (2665 -590);
PAINT MONO (2665 -590);
FORCEPROP 0 LASTPIN (2675 200) $PN B2
J 2
(2665 210);
DISPLAY 0.680851 (2665 210);
PAINT MONO (2665 210);
FORCEPROP 0 LASTPIN (2675 1000) $PN B3
J 2
(2665 1010);
DISPLAY 0.680851 (2665 1010);
PAINT MONO (2665 1010);
FORCEPROP 0 LASTPIN (2675 1800) $PN B4
J 2
(2665 1810);
DISPLAY 0.680851 (2665 1810);
PAINT MONO (2665 1810);
FORCEPROP 0 LASTPIN (2675 -650) $PN C1
J 2
(2665 -640);
DISPLAY 0.680851 (2665 -640);
PAINT MONO (2665 -640);
FORCEPROP 0 LASTPIN (2675 150) $PN C2
J 2
(2665 160);
DISPLAY 0.680851 (2665 160);
PAINT MONO (2665 160);
FORCEPROP 0 LASTPIN (2675 950) $PN C3
J 2
(2665 960);
DISPLAY 0.680851 (2665 960);
PAINT MONO (2665 960);
FORCEPROP 0 LASTPIN (2675 1750) $PN C4
J 2
(2665 1760);
DISPLAY 0.680851 (2665 1760);
PAINT MONO (2665 1760);
FORCEPROP 0 LASTPIN (2675 -700) $PN D1
J 2
(2665 -690);
DISPLAY 0.680851 (2665 -690);
PAINT MONO (2665 -690);
FORCEPROP 0 LASTPIN (2675 100) $PN D2
J 2
(2665 110);
DISPLAY 0.680851 (2665 110);
PAINT MONO (2665 110);
FORCEPROP 0 LASTPIN (2675 900) $PN D3
J 2
(2665 910);
DISPLAY 0.680851 (2665 910);
PAINT MONO (2665 910);
FORCEPROP 0 LASTPIN (2675 1700) $PN D4
J 2
(2665 1710);
DISPLAY 0.680851 (2665 1710);
PAINT MONO (2665 1710);
FORCEPROP 0 LASTPIN (2675 -750) $PN E1
J 2
(2665 -740);
DISPLAY 0.680851 (2665 -740);
PAINT MONO (2665 -740);
FORCEPROP 0 LASTPIN (2675 50) $PN E2
J 2
(2665 60);
DISPLAY 0.680851 (2665 60);
PAINT MONO (2665 60);
FORCEPROP 0 LASTPIN (2675 850) $PN E3
J 2
(2665 860);
DISPLAY 0.680851 (2665 860);
PAINT MONO (2665 860);
FORCEPROP 0 LASTPIN (2675 1650) $PN E4
J 2
(2665 1660);
DISPLAY 0.680851 (2665 1660);
PAINT MONO (2665 1660);
FORCEPROP 0 LASTPIN (2675 -800) $PN F1
J 2
(2665 -790);
DISPLAY 0.680851 (2665 -790);
PAINT MONO (2665 -790);
FORCEPROP 0 LASTPIN (2675 0) $PN F2
J 2
(2665 10);
DISPLAY 0.680851 (2665 10);
PAINT MONO (2665 10);
FORCEPROP 0 LASTPIN (2675 800) $PN F3
J 2
(2665 810);
DISPLAY 0.680851 (2665 810);
PAINT MONO (2665 810);
FORCEPROP 0 LASTPIN (2675 1600) $PN F4
J 2
(2665 1610);
DISPLAY 0.680851 (2665 1610);
PAINT MONO (2665 1610);
FORCEPROP 0 LASTPIN (2675 -850) $PN G1
J 2
(2665 -840);
DISPLAY 0.680851 (2665 -840);
PAINT MONO (2665 -840);
FORCEPROP 0 LASTPIN (2675 -50) $PN G2
J 2
(2665 -40);
DISPLAY 0.680851 (2665 -40);
PAINT MONO (2665 -40);
FORCEPROP 0 LASTPIN (2675 750) $PN G3
J 2
(2665 760);
DISPLAY 0.680851 (2665 760);
PAINT MONO (2665 760);
FORCEPROP 0 LASTPIN (2675 1550) $PN G4
J 2
(2665 1560);
DISPLAY 0.680851 (2665 1560);
PAINT MONO (2665 1560);
FORCEPROP 0 LASTPIN (2675 -900) $PN H1
J 2
(2665 -890);
DISPLAY 0.680851 (2665 -890);
PAINT MONO (2665 -890);
FORCEPROP 0 LASTPIN (2675 -100) $PN H2
J 2
(2665 -90);
DISPLAY 0.680851 (2665 -90);
PAINT MONO (2665 -90);
FORCEPROP 0 LASTPIN (2675 700) $PN H3
J 2
(2665 710);
DISPLAY 0.680851 (2665 710);
PAINT MONO (2665 710);
FORCEPROP 0 LASTPIN (2675 1500) $PN H4
J 2
(2665 1510);
DISPLAY 0.680851 (2665 1510);
PAINT MONO (2665 1510);
FORCEPROP 0 LASTPIN (2675 -950) $PN I1
J 2
(2665 -940);
DISPLAY 0.680851 (2665 -940);
PAINT MONO (2665 -940);
FORCEPROP 0 LASTPIN (2675 -150) $PN I2
J 2
(2665 -140);
DISPLAY 0.680851 (2665 -140);
PAINT MONO (2665 -140);
FORCEPROP 0 LASTPIN (2675 650) $PN I3
J 2
(2665 660);
DISPLAY 0.680851 (2665 660);
PAINT MONO (2665 660);
FORCEPROP 0 LASTPIN (2675 1450) $PN I4
J 2
(2665 1460);
DISPLAY 0.680851 (2665 1460);
PAINT MONO (2665 1460);
FORCEPROP 0 LASTPIN (2675 -1000) $PN J1
J 2
(2665 -990);
DISPLAY 0.680851 (2665 -990);
PAINT MONO (2665 -990);
FORCEPROP 0 LASTPIN (2675 -200) $PN J2
J 2
(2665 -190);
DISPLAY 0.680851 (2665 -190);
PAINT MONO (2665 -190);
FORCEPROP 0 LASTPIN (2675 600) $PN J3
J 2
(2665 610);
DISPLAY 0.680851 (2665 610);
PAINT MONO (2665 610);
FORCEPROP 0 LASTPIN (2675 1400) $PN J4
J 2
(2665 1410);
DISPLAY 0.680851 (2665 1410);
PAINT MONO (2665 1410);
FORCEPROP 0 LASTPIN (2675 -1050) $PN K1
J 2
(2665 -1040);
DISPLAY 0.680851 (2665 -1040);
PAINT MONO (2665 -1040);
FORCEPROP 0 LASTPIN (2675 -250) $PN K2
J 2
(2665 -240);
DISPLAY 0.680851 (2665 -240);
PAINT MONO (2665 -240);
FORCEPROP 0 LASTPIN (2675 550) $PN K3
J 2
(2665 560);
DISPLAY 0.680851 (2665 560);
PAINT MONO (2665 560);
FORCEPROP 0 LASTPIN (2675 1350) $PN K4
J 2
(2665 1360);
DISPLAY 0.680851 (2665 1360);
PAINT MONO (2665 1360);
FORCEPROP 0 LASTPIN (2675 -1100) $PN L1
J 2
(2665 -1090);
DISPLAY 0.680851 (2665 -1090);
PAINT MONO (2665 -1090);
FORCEPROP 0 LASTPIN (2675 -300) $PN L2
J 2
(2665 -290);
DISPLAY 0.680851 (2665 -290);
PAINT MONO (2665 -290);
FORCEPROP 0 LASTPIN (2675 500) $PN L3
J 2
(2665 510);
DISPLAY 0.680851 (2665 510);
PAINT MONO (2665 510);
FORCEPROP 0 LASTPIN (2675 1300) $PN L4
J 2
(2665 1310);
DISPLAY 0.680851 (2665 1310);
PAINT MONO (2665 1310);
FORCEPROP 0 LASTPIN (2675 -1150) $PN M1
J 2
(2665 -1140);
DISPLAY 0.680851 (2665 -1140);
PAINT MONO (2665 -1140);
FORCEPROP 0 LASTPIN (2675 -350) $PN M2
J 2
(2665 -340);
DISPLAY 0.680851 (2665 -340);
PAINT MONO (2665 -340);
FORCEPROP 0 LASTPIN (2675 450) $PN M3
J 2
(2665 460);
DISPLAY 0.680851 (2665 460);
PAINT MONO (2665 460);
FORCEPROP 0 LASTPIN (2675 1250) $PN M4
J 2
(2665 1260);
DISPLAY 0.680851 (2665 1260);
PAINT MONO (2665 1260);
FORCEPROP 0 LASTPIN (2675 -1200) $PN N1
J 2
(2665 -1190);
DISPLAY 0.680851 (2665 -1190);
PAINT MONO (2665 -1190);
FORCEPROP 0 LASTPIN (2675 -400) $PN N2
J 2
(2665 -390);
DISPLAY 0.680851 (2665 -390);
PAINT MONO (2665 -390);
FORCEPROP 0 LASTPIN (2675 400) $PN N3
J 2
(2665 410);
DISPLAY 0.680851 (2665 410);
PAINT MONO (2665 410);
FORCEPROP 0 LASTPIN (2675 1200) $PN N4
J 2
(2665 1210);
DISPLAY 0.680851 (2665 1210);
PAINT MONO (2665 1210);
FORCEPROP 2 LAST CDS_LIB pure_quanta
J 0
(3600 350);
DISPLAY INVISIBLE (3600 350);
FORCEPROP 1 LAST CDS_LMAN_SYM_OUTLINE -775,1650,775,-1650
J 0
(3600 350);
DISPLAY 0.468085 (3600 350);
PAINT GREEN (3600 350);
DISPLAY INVISIBLE (3600 350);
FORCEPROP 0 LAST VALUE CONN112_10137002-101LF
J 0
(2850 2250);
DISPLAY 1.021277 (2850 2250);
DISPLAY INVISIBLE (2850 2250);
FORCEPROP 1 LAST NEEDS_NO_SIZE TRUE
J 0
(3600 350);
DISPLAY 0.723404 (3600 350);
PAINT GREEN (3600 350);
DISPLAY INVISIBLE (3600 350);
FORCEPROP 1 LAST PATH I53
J 0
(3600 350);
DISPLAY 0.723404 (3600 350);
PAINT GREEN (3600 350);
DISPLAY INVISIBLE (3600 350);
FORCEPROP 0 LAST $SEC 2
J 0
(2850 2300);
DISPLAY 0.680851 (2850 2300);
PAINT MONO (2850 2300);
DISPLAY INVISIBLE (2850 2300);
FORCEPROP 0 LAST CDS_SEC 2
J 0
(2850 2300);
DISPLAY 1.021277 (2850 2300);
DISPLAY INVISIBLE (2850 2300);
FORCEADD OFFPAGE..5
(1400 0);
FORCEPROP 2 LAST $XR0 61 
J 0
(1176 0);
DISPLAY 0.638298 (1176 0);
PAINT MONO (1176 0);
FORCEPROP 2 LAST CDS_LIB standard
J 0
(1400 0);
DISPLAY INVISIBLE (1400 0);
FORCEPROP 1 LAST OFFPAGE TRUE
J 0
(1725 -125);
DISPLAY 0.872340 (1725 -125);
PAINT AQUA (1725 -125);
DISPLAY INVISIBLE (1725 -125);
FORCEPROP 1 LAST COMMENT_BODY TRUE
J 0
(1500 -75);
DISPLAY 1.170213 (1500 -75);
PAINT GREEN (1500 -75);
DISPLAY INVISIBLE (1500 -75);
FORCEPROP 2 LAST PATH I54
J 0
(1200 50);
DISPLAY 1.021277 (1200 50);
DISPLAY INVISIBLE (1200 50);
FORCEADD OFFPAGE..2
R 2
(1400 50);
FORCEPROP 2 LAST $XR0 61 
J 0
(1176 50);
DISPLAY 0.638298 (1176 50);
PAINT MONO (1176 50);
FORCEPROP 2 LAST CDS_LIB standard
J 0
(1400 50);
DISPLAY INVISIBLE (1400 50);
FORCEPROP 1 LAST OFFPAGE TRUE
J 2
(1075 -75);
DISPLAY 0.872340 (1075 -75);
PAINT AQUA (1075 -75);
DISPLAY INVISIBLE (1075 -75);
FORCEPROP 1 LAST COMMENT_BODY TRUE
J 2
(1445 -45);
DISPLAY 0.872340 (1445 -45);
PAINT GREEN (1445 -45);
DISPLAY INVISIBLE (1445 -45);
FORCEPROP 2 LAST PATH I55
J 0
(1200 100);
DISPLAY 1.021277 (1200 100);
DISPLAY INVISIBLE (1200 100);
FORCEADD OFFPAGE..5
(1400 150);
FORCEPROP 2 LAST $XR0 61 
J 0
(1176 150);
DISPLAY 0.638298 (1176 150);
PAINT MONO (1176 150);
FORCEPROP 2 LAST CDS_LIB standard
J 0
(1400 150);
DISPLAY INVISIBLE (1400 150);
FORCEPROP 1 LAST COMMENT_BODY TRUE
J 0
(1500 75);
DISPLAY 1.170213 (1500 75);
PAINT GREEN (1500 75);
DISPLAY INVISIBLE (1500 75);
FORCEPROP 1 LAST OFFPAGE TRUE
J 0
(1725 25);
DISPLAY 0.872340 (1725 25);
PAINT AQUA (1725 25);
DISPLAY INVISIBLE (1725 25);
FORCEPROP 2 LAST PATH I56
J 0
(1200 200);
DISPLAY 1.021277 (1200 200);
DISPLAY INVISIBLE (1200 200);
FORCEADD OFFPAGE..2
R 2
(1400 200);
FORCEPROP 2 LAST $XR0 61 
J 0
(1176 200);
DISPLAY 0.638298 (1176 200);
PAINT MONO (1176 200);
FORCEPROP 2 LAST CDS_LIB standard
J 0
(1400 200);
DISPLAY INVISIBLE (1400 200);
FORCEPROP 1 LAST COMMENT_BODY TRUE
J 2
(1445 105);
DISPLAY 0.872340 (1445 105);
PAINT GREEN (1445 105);
DISPLAY INVISIBLE (1445 105);
FORCEPROP 1 LAST OFFPAGE TRUE
J 2
(1075 75);
DISPLAY 0.872340 (1075 75);
PAINT AQUA (1075 75);
DISPLAY INVISIBLE (1075 75);
FORCEPROP 2 LAST PATH I57
J 0
(1200 250);
DISPLAY 1.021277 (1200 250);
DISPLAY INVISIBLE (1200 250);
FORCEADD OFFPAGE..1
(1375 450);
FORCEPROP 2 LAST $XR0 176 
J 0
(1093 450);
DISPLAY 0.638298 (1093 450);
PAINT MONO (1093 450);
FORCEPROP 2 LAST CDS_LIB standard
J 0
(1375 450);
DISPLAY INVISIBLE (1375 450);
FORCEPROP 1 LAST OFFPAGE TRUE
J 0
(1700 325);
DISPLAY 0.872340 (1700 325);
PAINT AQUA (1700 325);
DISPLAY INVISIBLE (1700 325);
FORCEPROP 1 LAST COMMENT_BODY TRUE
J 0
(1500 350);
DISPLAY 0.872340 (1500 350);
PAINT GREEN (1500 350);
DISPLAY INVISIBLE (1500 350);
FORCEPROP 2 LAST PATH I58
J 0
(1100 500);
DISPLAY 1.021277 (1100 500);
DISPLAY INVISIBLE (1100 500);
FORCEADD OFFPAGE..1
(1375 500);
FORCEPROP 2 LAST $XR0 176 
J 0
(1093 500);
DISPLAY 0.638298 (1093 500);
PAINT MONO (1093 500);
FORCEPROP 2 LAST CDS_LIB standard
J 0
(1375 500);
DISPLAY INVISIBLE (1375 500);
FORCEPROP 1 LAST COMMENT_BODY TRUE
J 0
(1500 400);
DISPLAY 0.872340 (1500 400);
PAINT GREEN (1500 400);
DISPLAY INVISIBLE (1500 400);
FORCEPROP 1 LAST OFFPAGE TRUE
J 0
(1700 375);
DISPLAY 0.872340 (1700 375);
PAINT AQUA (1700 375);
DISPLAY INVISIBLE (1700 375);
FORCEPROP 2 LAST PATH I59
J 0
(1100 550);
DISPLAY 1.021277 (1100 550);
DISPLAY INVISIBLE (1100 550);
FORCEADD OFFPAGE..2
R 2
(-3375 -725);
FORCEPROP 2 LAST $XR0 61 
J 0
(-3629 -725);
DISPLAY 0.638298 (-3629 -725);
PAINT MONO (-3629 -725);
FORCEPROP 2 LAST PATH I6
J 0
(-3625 -675);
DISPLAY 1.021277 (-3625 -675);
DISPLAY INVISIBLE (-3625 -675);
FORCEPROP 1 LAST COMMENT_BODY TRUE
J 2
(-3330 -820);
DISPLAY 0.872340 (-3330 -820);
PAINT GREEN (-3330 -820);
DISPLAY INVISIBLE (-3330 -820);
FORCEPROP 1 LAST OFFPAGE TRUE
J 2
(-3700 -850);
DISPLAY 0.872340 (-3700 -850);
PAINT AQUA (-3700 -850);
DISPLAY INVISIBLE (-3700 -850);
FORCEPROP 2 LAST CDS_LIB standard
J 0
(-3375 -725);
DISPLAY INVISIBLE (-3375 -725);
FORCEADD OFFPAGE..1
(1375 650);
FORCEPROP 2 LAST $XR0 177 
J 0
(1093 650);
DISPLAY 0.638298 (1093 650);
PAINT MONO (1093 650);
FORCEPROP 2 LAST CDS_LIB standard
J 0
(1375 650);
DISPLAY INVISIBLE (1375 650);
FORCEPROP 1 LAST COMMENT_BODY TRUE
J 0
(1500 550);
DISPLAY 0.872340 (1500 550);
PAINT GREEN (1500 550);
DISPLAY INVISIBLE (1500 550);
FORCEPROP 1 LAST OFFPAGE TRUE
J 0
(1700 525);
DISPLAY 0.872340 (1700 525);
PAINT AQUA (1700 525);
DISPLAY INVISIBLE (1700 525);
FORCEPROP 2 LAST PATH I60
J 0
(1100 700);
DISPLAY 1.021277 (1100 700);
DISPLAY INVISIBLE (1100 700);
FORCEADD OFFPAGE..1
(1375 600);
FORCEPROP 2 LAST $XR0 177 
J 0
(1093 600);
DISPLAY 0.638298 (1093 600);
PAINT MONO (1093 600);
FORCEPROP 2 LAST CDS_LIB standard
J 0
(1375 600);
DISPLAY INVISIBLE (1375 600);
FORCEPROP 1 LAST OFFPAGE TRUE
J 0
(1700 475);
DISPLAY 0.872340 (1700 475);
PAINT AQUA (1700 475);
DISPLAY INVISIBLE (1700 475);
FORCEPROP 1 LAST COMMENT_BODY TRUE
J 0
(1500 500);
DISPLAY 0.872340 (1500 500);
PAINT GREEN (1500 500);
DISPLAY INVISIBLE (1500 500);
FORCEPROP 2 LAST PATH I61
J 0
(1100 650);
DISPLAY 1.021277 (1100 650);
DISPLAY INVISIBLE (1100 650);
FORCEADD OFFPAGE..2
R 2
(1375 800);
FORCEPROP 2 LAST $XR0 61 
J 0
(1121 800);
DISPLAY 0.638298 (1121 800);
PAINT MONO (1121 800);
FORCEPROP 2 LAST CDS_LIB standard
J 0
(1375 800);
DISPLAY INVISIBLE (1375 800);
FORCEPROP 1 LAST COMMENT_BODY TRUE
J 2
(1420 705);
DISPLAY 0.872340 (1420 705);
PAINT GREEN (1420 705);
DISPLAY INVISIBLE (1420 705);
FORCEPROP 1 LAST OFFPAGE TRUE
J 2
(1050 675);
DISPLAY 0.872340 (1050 675);
PAINT AQUA (1050 675);
DISPLAY INVISIBLE (1050 675);
FORCEPROP 2 LAST PATH I62
J 0
(1125 850);
DISPLAY 1.021277 (1125 850);
DISPLAY INVISIBLE (1125 850);
FORCEADD OFFPAGE..5
(1375 750);
FORCEPROP 2 LAST $XR0 61 
J 0
(1121 750);
DISPLAY 0.638298 (1121 750);
PAINT MONO (1121 750);
FORCEPROP 2 LAST CDS_LIB standard
J 0
(1375 750);
DISPLAY INVISIBLE (1375 750);
FORCEPROP 1 LAST COMMENT_BODY TRUE
J 0
(1475 675);
DISPLAY 1.170213 (1475 675);
PAINT GREEN (1475 675);
DISPLAY INVISIBLE (1475 675);
FORCEPROP 1 LAST OFFPAGE TRUE
J 0
(1700 625);
DISPLAY 0.872340 (1700 625);
PAINT AQUA (1700 625);
DISPLAY INVISIBLE (1700 625);
FORCEPROP 2 LAST PATH I63
J 0
(1125 800);
DISPLAY 1.021277 (1125 800);
DISPLAY INVISIBLE (1125 800);
FORCEADD OFFPAGE..5
(1375 900);
FORCEPROP 2 LAST $XR0 61 
J 0
(1121 900);
DISPLAY 0.638298 (1121 900);
PAINT MONO (1121 900);
FORCEPROP 2 LAST CDS_LIB standard
J 0
(1375 900);
DISPLAY INVISIBLE (1375 900);
FORCEPROP 1 LAST COMMENT_BODY TRUE
J 0
(1475 825);
DISPLAY 1.170213 (1475 825);
PAINT GREEN (1475 825);
DISPLAY INVISIBLE (1475 825);
FORCEPROP 1 LAST OFFPAGE TRUE
J 0
(1700 775);
DISPLAY 0.872340 (1700 775);
PAINT AQUA (1700 775);
DISPLAY INVISIBLE (1700 775);
FORCEPROP 2 LAST PATH I64
J 0
(1125 950);
DISPLAY 1.021277 (1125 950);
DISPLAY INVISIBLE (1125 950);
FORCEADD OFFPAGE..2
R 2
(1375 950);
FORCEPROP 2 LAST $XR0 61 
J 0
(1121 950);
DISPLAY 0.638298 (1121 950);
PAINT MONO (1121 950);
FORCEPROP 2 LAST CDS_LIB standard
J 0
(1375 950);
DISPLAY INVISIBLE (1375 950);
FORCEPROP 1 LAST COMMENT_BODY TRUE
J 2
(1420 855);
DISPLAY 0.872340 (1420 855);
PAINT GREEN (1420 855);
DISPLAY INVISIBLE (1420 855);
FORCEPROP 1 LAST OFFPAGE TRUE
J 2
(1050 825);
DISPLAY 0.872340 (1050 825);
PAINT AQUA (1050 825);
DISPLAY INVISIBLE (1050 825);
FORCEPROP 2 LAST PATH I65
J 0
(1125 1000);
DISPLAY 1.021277 (1125 1000);
DISPLAY INVISIBLE (1125 1000);
FORCEADD OFFPAGE..1
(1375 1300);
FORCEPROP 2 LAST $XR0 176 
J 0
(1093 1300);
DISPLAY 0.638298 (1093 1300);
PAINT MONO (1093 1300);
FORCEPROP 2 LAST CDS_LIB standard
J 0
(1375 1300);
DISPLAY INVISIBLE (1375 1300);
FORCEPROP 1 LAST OFFPAGE TRUE
J 0
(1700 1175);
DISPLAY 0.872340 (1700 1175);
PAINT AQUA (1700 1175);
DISPLAY INVISIBLE (1700 1175);
FORCEPROP 1 LAST COMMENT_BODY TRUE
J 0
(1500 1200);
DISPLAY 0.872340 (1500 1200);
PAINT GREEN (1500 1200);
DISPLAY INVISIBLE (1500 1200);
FORCEPROP 2 LAST PATH I68
J 0
(1100 1350);
DISPLAY 1.021277 (1100 1350);
DISPLAY INVISIBLE (1100 1350);
FORCEADD OFFPAGE..1
(1375 1450);
FORCEPROP 2 LAST $XR0 177 
J 0
(1093 1450);
DISPLAY 0.638298 (1093 1450);
PAINT MONO (1093 1450);
FORCEPROP 2 LAST CDS_LIB standard
J 0
(1375 1450);
DISPLAY INVISIBLE (1375 1450);
FORCEPROP 1 LAST COMMENT_BODY TRUE
J 0
(1500 1350);
DISPLAY 0.872340 (1500 1350);
PAINT GREEN (1500 1350);
DISPLAY INVISIBLE (1500 1350);
FORCEPROP 1 LAST OFFPAGE TRUE
J 0
(1700 1325);
DISPLAY 0.872340 (1700 1325);
PAINT AQUA (1700 1325);
DISPLAY INVISIBLE (1700 1325);
FORCEPROP 2 LAST PATH I69
J 0
(1100 1500);
DISPLAY 1.021277 (1100 1500);
DISPLAY INVISIBLE (1100 1500);
FORCEADD OFFPAGE..5
(-3375 -625);
FORCEPROP 2 LAST $XR0 61 
J 0
(-3629 -625);
DISPLAY 0.638298 (-3629 -625);
PAINT MONO (-3629 -625);
FORCEPROP 2 LAST PATH I7
J 0
(-3625 -575);
DISPLAY 1.021277 (-3625 -575);
DISPLAY INVISIBLE (-3625 -575);
FORCEPROP 1 LAST COMMENT_BODY TRUE
J 0
(-3275 -700);
DISPLAY 1.170213 (-3275 -700);
PAINT GREEN (-3275 -700);
DISPLAY INVISIBLE (-3275 -700);
FORCEPROP 1 LAST OFFPAGE TRUE
J 0
(-3050 -750);
DISPLAY 0.872340 (-3050 -750);
PAINT AQUA (-3050 -750);
DISPLAY INVISIBLE (-3050 -750);
FORCEPROP 2 LAST CDS_LIB standard
J 0
(-3375 -625);
DISPLAY INVISIBLE (-3375 -625);
FORCEADD OFFPAGE..1
(1375 1350);
FORCEPROP 2 LAST $XR0 176 
J 0
(1093 1350);
DISPLAY 0.638298 (1093 1350);
PAINT MONO (1093 1350);
FORCEPROP 2 LAST CDS_LIB standard
J 0
(1375 1350);
DISPLAY INVISIBLE (1375 1350);
FORCEPROP 1 LAST COMMENT_BODY TRUE
J 0
(1500 1250);
DISPLAY 0.872340 (1500 1250);
PAINT GREEN (1500 1250);
DISPLAY INVISIBLE (1500 1250);
FORCEPROP 1 LAST OFFPAGE TRUE
J 0
(1700 1225);
DISPLAY 0.872340 (1700 1225);
PAINT AQUA (1700 1225);
DISPLAY INVISIBLE (1700 1225);
FORCEPROP 2 LAST PATH I70
J 0
(1100 1400);
DISPLAY 1.021277 (1100 1400);
DISPLAY INVISIBLE (1100 1400);
FORCEADD OFFPAGE..1
(1375 1500);
FORCEPROP 2 LAST $XR0 177 
J 0
(1093 1500);
DISPLAY 0.638298 (1093 1500);
PAINT MONO (1093 1500);
FORCEPROP 2 LAST CDS_LIB standard
J 0
(1375 1500);
DISPLAY INVISIBLE (1375 1500);
FORCEPROP 1 LAST OFFPAGE TRUE
J 0
(1700 1375);
DISPLAY 0.872340 (1700 1375);
PAINT AQUA (1700 1375);
DISPLAY INVISIBLE (1700 1375);
FORCEPROP 1 LAST COMMENT_BODY TRUE
J 0
(1500 1400);
DISPLAY 0.872340 (1500 1400);
PAINT GREEN (1500 1400);
DISPLAY INVISIBLE (1500 1400);
FORCEPROP 2 LAST PATH I71
J 0
(1100 1550);
DISPLAY 1.021277 (1100 1550);
DISPLAY INVISIBLE (1100 1550);
FORCEADD OFFPAGE..2
R 2
(1375 1650);
FORCEPROP 2 LAST $XR0 61 
J 0
(1121 1650);
DISPLAY 0.638298 (1121 1650);
PAINT MONO (1121 1650);
FORCEPROP 2 LAST CDS_LIB standard
J 0
(1375 1650);
DISPLAY INVISIBLE (1375 1650);
FORCEPROP 1 LAST OFFPAGE TRUE
J 2
(1050 1525);
DISPLAY 0.872340 (1050 1525);
PAINT AQUA (1050 1525);
DISPLAY INVISIBLE (1050 1525);
FORCEPROP 1 LAST COMMENT_BODY TRUE
J 2
(1420 1555);
DISPLAY 0.872340 (1420 1555);
PAINT GREEN (1420 1555);
DISPLAY INVISIBLE (1420 1555);
FORCEPROP 2 LAST PATH I72
J 0
(1125 1700);
DISPLAY 1.021277 (1125 1700);
DISPLAY INVISIBLE (1125 1700);
FORCEADD OFFPAGE..5
(1375 1600);
FORCEPROP 2 LAST $XR0 61 
J 0
(1121 1600);
DISPLAY 0.638298 (1121 1600);
PAINT MONO (1121 1600);
FORCEPROP 2 LAST CDS_LIB standard
J 0
(1375 1600);
DISPLAY INVISIBLE (1375 1600);
FORCEPROP 1 LAST OFFPAGE TRUE
J 0
(1700 1475);
DISPLAY 0.872340 (1700 1475);
PAINT AQUA (1700 1475);
DISPLAY INVISIBLE (1700 1475);
FORCEPROP 1 LAST COMMENT_BODY TRUE
J 0
(1475 1525);
DISPLAY 1.170213 (1475 1525);
PAINT GREEN (1475 1525);
DISPLAY INVISIBLE (1475 1525);
FORCEPROP 2 LAST PATH I73
J 0
(1125 1650);
DISPLAY 1.021277 (1125 1650);
DISPLAY INVISIBLE (1125 1650);
FORCEADD OFFPAGE..5
(1375 1750);
FORCEPROP 2 LAST $XR0 61 
J 0
(1121 1750);
DISPLAY 0.638298 (1121 1750);
PAINT MONO (1121 1750);
FORCEPROP 2 LAST CDS_LIB standard
J 0
(1375 1750);
DISPLAY INVISIBLE (1375 1750);
FORCEPROP 1 LAST COMMENT_BODY TRUE
J 0
(1475 1675);
DISPLAY 1.170213 (1475 1675);
PAINT GREEN (1475 1675);
DISPLAY INVISIBLE (1475 1675);
FORCEPROP 1 LAST OFFPAGE TRUE
J 0
(1700 1625);
DISPLAY 0.872340 (1700 1625);
PAINT AQUA (1700 1625);
DISPLAY INVISIBLE (1700 1625);
FORCEPROP 2 LAST PATH I74
J 0
(1125 1800);
DISPLAY 1.021277 (1125 1800);
DISPLAY INVISIBLE (1125 1800);
FORCEADD OFFPAGE..2
R 2
(1375 1800);
FORCEPROP 2 LAST $XR0 61 
J 0
(1121 1800);
DISPLAY 0.638298 (1121 1800);
PAINT MONO (1121 1800);
FORCEPROP 2 LAST CDS_LIB standard
J 0
(1375 1800);
DISPLAY INVISIBLE (1375 1800);
FORCEPROP 1 LAST COMMENT_BODY TRUE
J 2
(1420 1705);
DISPLAY 0.872340 (1420 1705);
PAINT GREEN (1420 1705);
DISPLAY INVISIBLE (1420 1705);
FORCEPROP 1 LAST OFFPAGE TRUE
J 2
(1050 1675);
DISPLAY 0.872340 (1050 1675);
PAINT AQUA (1050 1675);
DISPLAY INVISIBLE (1050 1675);
FORCEPROP 2 LAST PATH I75
J 0
(1125 1850);
DISPLAY 1.021277 (1125 1850);
DISPLAY INVISIBLE (1125 1850);
FORCEADD CONN112_10137002101LF..1
(-1175 425);
FORCEPROP 1 LAST PART_NUMBER DFHSB2FR012
J 0
(-1925 2175);
DISPLAY 0.723404 (-1925 2175);
PAINT GREEN (-1925 2175);
DISPLAY INVISIBLE (-1925 2175);
FORCEPROP 2 LAST PART_TYPE THLF
J 0
(-1925 2300);
DISPLAY 1.021277 (-1925 2300);
FORCEPROP 1 LAST MATERIAL IO
J 0
(-1920 2107);
DISPLAY 0.723404 (-1920 2107);
PAINT GREEN (-1920 2107);
FORCEPROP 1 LAST LOCATION J109
J 0
(-1925 2225);
DISPLAY 0.723404 (-1925 2225);
PAINT GREEN (-1925 2225);
FORCEPROP 0 LASTPIN (-2100 -475) $PN A5
J 2
(-2110 -465);
DISPLAY 0.680851 (-2110 -465);
PAINT MONO (-2110 -465);
FORCEPROP 0 LASTPIN (-2100 325) $PN A6
J 2
(-2110 335);
DISPLAY 0.680851 (-2110 335);
PAINT MONO (-2110 335);
FORCEPROP 0 LASTPIN (-2100 1125) $PN A7
J 2
(-2110 1135);
DISPLAY 0.680851 (-2110 1135);
PAINT MONO (-2110 1135);
FORCEPROP 0 LASTPIN (-2100 1925) $PN A8
J 2
(-2110 1935);
DISPLAY 0.680851 (-2110 1935);
PAINT MONO (-2110 1935);
FORCEPROP 0 LASTPIN (-2100 -525) $PN B5
J 2
(-2110 -515);
DISPLAY 0.680851 (-2110 -515);
PAINT MONO (-2110 -515);
FORCEPROP 0 LASTPIN (-2100 275) $PN B6
J 2
(-2110 285);
DISPLAY 0.680851 (-2110 285);
PAINT MONO (-2110 285);
FORCEPROP 0 LASTPIN (-2100 1075) $PN B7
J 2
(-2110 1085);
DISPLAY 0.680851 (-2110 1085);
PAINT MONO (-2110 1085);
FORCEPROP 0 LASTPIN (-2100 1875) $PN B8
J 2
(-2110 1885);
DISPLAY 0.680851 (-2110 1885);
PAINT MONO (-2110 1885);
FORCEPROP 0 LASTPIN (-2100 -575) $PN C5
J 2
(-2110 -565);
DISPLAY 0.680851 (-2110 -565);
PAINT MONO (-2110 -565);
FORCEPROP 0 LASTPIN (-2100 225) $PN C6
J 2
(-2110 235);
DISPLAY 0.680851 (-2110 235);
PAINT MONO (-2110 235);
FORCEPROP 0 LASTPIN (-2100 1025) $PN C7
J 2
(-2110 1035);
DISPLAY 0.680851 (-2110 1035);
PAINT MONO (-2110 1035);
FORCEPROP 0 LASTPIN (-2100 1825) $PN C8
J 2
(-2110 1835);
DISPLAY 0.680851 (-2110 1835);
PAINT MONO (-2110 1835);
FORCEPROP 0 LASTPIN (-2100 -625) $PN D5
J 2
(-2110 -615);
DISPLAY 0.680851 (-2110 -615);
PAINT MONO (-2110 -615);
FORCEPROP 0 LASTPIN (-2100 175) $PN D6
J 2
(-2110 185);
DISPLAY 0.680851 (-2110 185);
PAINT MONO (-2110 185);
FORCEPROP 0 LASTPIN (-2100 975) $PN D7
J 2
(-2110 985);
DISPLAY 0.680851 (-2110 985);
PAINT MONO (-2110 985);
FORCEPROP 0 LASTPIN (-2100 1775) $PN D8
J 2
(-2110 1785);
DISPLAY 0.680851 (-2110 1785);
PAINT MONO (-2110 1785);
FORCEPROP 0 LASTPIN (-2100 -675) $PN E5
J 2
(-2110 -665);
DISPLAY 0.680851 (-2110 -665);
PAINT MONO (-2110 -665);
FORCEPROP 0 LASTPIN (-2100 125) $PN E6
J 2
(-2110 135);
DISPLAY 0.680851 (-2110 135);
PAINT MONO (-2110 135);
FORCEPROP 0 LASTPIN (-2100 925) $PN E7
J 2
(-2110 935);
DISPLAY 0.680851 (-2110 935);
PAINT MONO (-2110 935);
FORCEPROP 0 LASTPIN (-2100 1725) $PN E8
J 2
(-2110 1735);
DISPLAY 0.680851 (-2110 1735);
PAINT MONO (-2110 1735);
FORCEPROP 0 LASTPIN (-2100 -725) $PN F5
J 2
(-2110 -715);
DISPLAY 0.680851 (-2110 -715);
PAINT MONO (-2110 -715);
FORCEPROP 0 LASTPIN (-2100 75) $PN F6
J 2
(-2110 85);
DISPLAY 0.680851 (-2110 85);
PAINT MONO (-2110 85);
FORCEPROP 0 LASTPIN (-2100 875) $PN F7
J 2
(-2110 885);
DISPLAY 0.680851 (-2110 885);
PAINT MONO (-2110 885);
FORCEPROP 0 LASTPIN (-2100 1675) $PN F8
J 2
(-2110 1685);
DISPLAY 0.680851 (-2110 1685);
PAINT MONO (-2110 1685);
FORCEPROP 0 LASTPIN (-2100 -775) $PN G5
J 2
(-2110 -765);
DISPLAY 0.680851 (-2110 -765);
PAINT MONO (-2110 -765);
FORCEPROP 0 LASTPIN (-2100 25) $PN G6
J 2
(-2110 35);
DISPLAY 0.680851 (-2110 35);
PAINT MONO (-2110 35);
FORCEPROP 0 LASTPIN (-2100 825) $PN G7
J 2
(-2110 835);
DISPLAY 0.680851 (-2110 835);
PAINT MONO (-2110 835);
FORCEPROP 0 LASTPIN (-2100 1625) $PN G8
J 2
(-2110 1635);
DISPLAY 0.680851 (-2110 1635);
PAINT MONO (-2110 1635);
FORCEPROP 0 LASTPIN (-2100 -825) $PN H5
J 2
(-2110 -815);
DISPLAY 0.680851 (-2110 -815);
PAINT MONO (-2110 -815);
FORCEPROP 0 LASTPIN (-2100 -25) $PN H6
J 2
(-2110 -15);
DISPLAY 0.680851 (-2110 -15);
PAINT MONO (-2110 -15);
FORCEPROP 0 LASTPIN (-2100 775) $PN H7
J 2
(-2110 785);
DISPLAY 0.680851 (-2110 785);
PAINT MONO (-2110 785);
FORCEPROP 0 LASTPIN (-2100 1575) $PN H8
J 2
(-2110 1585);
DISPLAY 0.680851 (-2110 1585);
PAINT MONO (-2110 1585);
FORCEPROP 0 LASTPIN (-2100 -875) $PN I5
J 2
(-2110 -865);
DISPLAY 0.680851 (-2110 -865);
PAINT MONO (-2110 -865);
FORCEPROP 0 LASTPIN (-2100 -75) $PN I6
J 2
(-2110 -65);
DISPLAY 0.680851 (-2110 -65);
PAINT MONO (-2110 -65);
FORCEPROP 0 LASTPIN (-2100 725) $PN I7
J 2
(-2110 735);
DISPLAY 0.680851 (-2110 735);
PAINT MONO (-2110 735);
FORCEPROP 0 LASTPIN (-2100 1525) $PN I8
J 2
(-2110 1535);
DISPLAY 0.680851 (-2110 1535);
PAINT MONO (-2110 1535);
FORCEPROP 0 LASTPIN (-2100 -925) $PN J5
J 2
(-2110 -915);
DISPLAY 0.680851 (-2110 -915);
PAINT MONO (-2110 -915);
FORCEPROP 0 LASTPIN (-2100 -125) $PN J6
J 2
(-2110 -115);
DISPLAY 0.680851 (-2110 -115);
PAINT MONO (-2110 -115);
FORCEPROP 0 LASTPIN (-2100 675) $PN J7
J 2
(-2110 685);
DISPLAY 0.680851 (-2110 685);
PAINT MONO (-2110 685);
FORCEPROP 0 LASTPIN (-2100 1475) $PN J8
J 2
(-2110 1485);
DISPLAY 0.680851 (-2110 1485);
PAINT MONO (-2110 1485);
FORCEPROP 0 LASTPIN (-2100 -975) $PN K5
J 2
(-2110 -965);
DISPLAY 0.680851 (-2110 -965);
PAINT MONO (-2110 -965);
FORCEPROP 0 LASTPIN (-2100 -175) $PN K6
J 2
(-2110 -165);
DISPLAY 0.680851 (-2110 -165);
PAINT MONO (-2110 -165);
FORCEPROP 0 LASTPIN (-2100 625) $PN K7
J 2
(-2110 635);
DISPLAY 0.680851 (-2110 635);
PAINT MONO (-2110 635);
FORCEPROP 0 LASTPIN (-2100 1425) $PN K8
J 2
(-2110 1435);
DISPLAY 0.680851 (-2110 1435);
PAINT MONO (-2110 1435);
FORCEPROP 0 LASTPIN (-2100 -1025) $PN L5
J 2
(-2110 -1015);
DISPLAY 0.680851 (-2110 -1015);
PAINT MONO (-2110 -1015);
FORCEPROP 0 LASTPIN (-2100 -225) $PN L6
J 2
(-2110 -215);
DISPLAY 0.680851 (-2110 -215);
PAINT MONO (-2110 -215);
FORCEPROP 0 LASTPIN (-2100 575) $PN L7
J 2
(-2110 585);
DISPLAY 0.680851 (-2110 585);
PAINT MONO (-2110 585);
FORCEPROP 0 LASTPIN (-2100 1375) $PN L8
J 2
(-2110 1385);
DISPLAY 0.680851 (-2110 1385);
PAINT MONO (-2110 1385);
FORCEPROP 0 LASTPIN (-2100 -1075) $PN M5
J 2
(-2110 -1065);
DISPLAY 0.680851 (-2110 -1065);
PAINT MONO (-2110 -1065);
FORCEPROP 0 LASTPIN (-2100 -275) $PN M6
J 2
(-2110 -265);
DISPLAY 0.680851 (-2110 -265);
PAINT MONO (-2110 -265);
FORCEPROP 0 LASTPIN (-2100 525) $PN M7
J 2
(-2110 535);
DISPLAY 0.680851 (-2110 535);
PAINT MONO (-2110 535);
FORCEPROP 0 LASTPIN (-2100 1325) $PN M8
J 2
(-2110 1335);
DISPLAY 0.680851 (-2110 1335);
PAINT MONO (-2110 1335);
FORCEPROP 0 LASTPIN (-2100 -1125) $PN N5
J 2
(-2110 -1115);
DISPLAY 0.680851 (-2110 -1115);
PAINT MONO (-2110 -1115);
FORCEPROP 0 LASTPIN (-2100 -325) $PN N6
J 2
(-2110 -315);
DISPLAY 0.680851 (-2110 -315);
PAINT MONO (-2110 -315);
FORCEPROP 0 LASTPIN (-2100 475) $PN N7
J 2
(-2110 485);
DISPLAY 0.680851 (-2110 485);
PAINT MONO (-2110 485);
FORCEPROP 0 LASTPIN (-2100 1275) $PN N8
J 2
(-2110 1285);
DISPLAY 0.680851 (-2110 1285);
PAINT MONO (-2110 1285);
FORCEPROP 1 LAST PATH I76
J 0
(-1175 425);
DISPLAY 0.723404 (-1175 425);
PAINT GREEN (-1175 425);
DISPLAY INVISIBLE (-1175 425);
FORCEPROP 0 LAST VALUE CONN112_10137002-101LF
J 0
(-1900 2425);
DISPLAY 1.021277 (-1900 2425);
DISPLAY INVISIBLE (-1900 2425);
FORCEPROP 1 LAST NEEDS_NO_SIZE TRUE
J 0
(-1175 425);
DISPLAY 0.723404 (-1175 425);
PAINT GREEN (-1175 425);
DISPLAY INVISIBLE (-1175 425);
FORCEPROP 1 LAST CDS_LMAN_SYM_OUTLINE -775,1650,775,-1650
J 0
(-1175 425);
DISPLAY 0.468085 (-1175 425);
PAINT GREEN (-1175 425);
DISPLAY INVISIBLE (-1175 425);
FORCEPROP 2 LAST CDS_LIB pure_quanta
J 0
(-1175 425);
DISPLAY INVISIBLE (-1175 425);
FORCEPROP 0 LAST $SEC 1
J 0
(-1925 2350);
DISPLAY 0.680851 (-1925 2350);
PAINT MONO (-1925 2350);
DISPLAY INVISIBLE (-1925 2350);
FORCEPROP 0 LAST CDS_SEC 1
J 0
(-1925 2350);
DISPLAY 1.021277 (-1925 2350);
DISPLAY INVISIBLE (-1925 2350);
FORCEADD OFFPAGE..2
R 2
(-3375 -575);
FORCEPROP 2 LAST $XR0 61 
J 0
(-3629 -575);
DISPLAY 0.638298 (-3629 -575);
PAINT MONO (-3629 -575);
FORCEPROP 2 LAST PATH I8
J 0
(-3625 -525);
DISPLAY 1.021277 (-3625 -525);
DISPLAY INVISIBLE (-3625 -525);
FORCEPROP 1 LAST COMMENT_BODY TRUE
J 2
(-3330 -670);
DISPLAY 0.872340 (-3330 -670);
PAINT GREEN (-3330 -670);
DISPLAY INVISIBLE (-3330 -670);
FORCEPROP 1 LAST OFFPAGE TRUE
J 2
(-3700 -700);
DISPLAY 0.872340 (-3700 -700);
PAINT AQUA (-3700 -700);
DISPLAY INVISIBLE (-3700 -700);
FORCEPROP 2 LAST CDS_LIB standard
J 0
(-3375 -575);
DISPLAY INVISIBLE (-3375 -575);
FORCEADD OFFPAGE..4
R 2
(1400 -550);
FORCEPROP 2 LAST $XR0 151 
J 0
(1118 -550);
DISPLAY 0.638298 (1118 -550);
PAINT MONO (1118 -550);
FORCEPROP 1 LAST COMMENT_BODY TRUE
J 2
(1425 -650);
DISPLAY 0.872340 (1425 -650);
PAINT GREEN (1425 -650);
DISPLAY INVISIBLE (1425 -650);
FORCEPROP 1 LAST OFFPAGE TRUE
J 2
(1075 -675);
DISPLAY 0.872340 (1075 -675);
PAINT GREEN (1075 -675);
DISPLAY INVISIBLE (1075 -675);
FORCEPROP 2 LAST CDS_LIB standard
J 0
(1400 -550);
DISPLAY INVISIBLE (1400 -550);
FORCEPROP 2 LAST PATH I83
J 0
(1125 -500);
DISPLAY 1.021277 (1125 -500);
DISPLAY INVISIBLE (1125 -500);
FORCEADD OFFPAGE..5
(1375 1050);
FORCEPROP 2 LAST $XR0 148 
J 0
(1120 1050);
DISPLAY 0.638298 (1120 1050);
PAINT MONO (1120 1050);
FORCEPROP 2 LAST CDS_LIB standard
J 0
(1375 1050);
DISPLAY INVISIBLE (1375 1050);
FORCEPROP 1 LAST OFFPAGE TRUE
J 0
(1700 925);
DISPLAY 0.872340 (1700 925);
PAINT AQUA (1700 925);
DISPLAY INVISIBLE (1700 925);
FORCEPROP 1 LAST COMMENT_BODY TRUE
J 0
(1475 975);
DISPLAY 1.170213 (1475 975);
PAINT GREEN (1475 975);
DISPLAY INVISIBLE (1475 975);
FORCEPROP 2 LAST PATH I84
J 0
(1125 1100);
DISPLAY 1.021277 (1125 1100);
DISPLAY INVISIBLE (1125 1100);
FORCEADD OFFPAGE..2
R 2
(1400 -400);
FORCEPROP 2 LAST $XR0 147 
J 0
(1145 -400);
DISPLAY 0.638298 (1145 -400);
PAINT MONO (1145 -400);
FORCEPROP 2 LAST CDS_LIB standard
J 0
(1400 -400);
DISPLAY INVISIBLE (1400 -400);
FORCEPROP 1 LAST COMMENT_BODY TRUE
J 2
(1445 -495);
DISPLAY 0.872340 (1445 -495);
PAINT GREEN (1445 -495);
DISPLAY INVISIBLE (1445 -495);
FORCEPROP 1 LAST OFFPAGE TRUE
J 2
(1075 -525);
DISPLAY 0.872340 (1075 -525);
PAINT AQUA (1075 -525);
DISPLAY INVISIBLE (1075 -525);
FORCEPROP 2 LAST PATH I85
J 0
(1200 -350);
DISPLAY 1.021277 (1200 -350);
DISPLAY INVISIBLE (1200 -350);
FORCEADD OFFPAGE..3
R 2
(-3375 -475);
FORCEPROP 2 LAST $XR0 234 
J 0
(-3655 -475);
DISPLAY 0.638298 (-3655 -475);
PAINT MONO (-3655 -475);
FORCEPROP 2 LAST CDS_LIB standard
J 0
(-3375 -475);
DISPLAY INVISIBLE (-3375 -475);
FORCEPROP 1 LAST OFFPAGE TRUE
J 2
(-3700 -600);
DISPLAY 0.872340 (-3700 -600);
DISPLAY INVISIBLE (-3700 -600);
FORCEPROP 1 LAST COMMENT_BODY TRUE
J 2
(-3325 -575);
DISPLAY 0.872340 (-3325 -575);
PAINT GREEN (-3325 -575);
DISPLAY INVISIBLE (-3325 -575);
FORCEPROP 2 LAST PATH I86
J 0
(-3650 -425);
DISPLAY 1.021277 (-3650 -425);
DISPLAY INVISIBLE (-3650 -425);
FORCEADD OFFPAGE..4
R 2
(-3375 1125);
FORCEPROP 2 LAST $XR0 234 
J 0
(-3627 1125);
DISPLAY 0.638298 (-3627 1125);
PAINT MONO (-3627 1125);
FORCEPROP 1 LAST OFFPAGE TRUE
J 2
(-3700 1000);
DISPLAY 0.872340 (-3700 1000);
PAINT GREEN (-3700 1000);
DISPLAY INVISIBLE (-3700 1000);
FORCEPROP 1 LAST COMMENT_BODY TRUE
J 2
(-3350 1025);
DISPLAY 0.872340 (-3350 1025);
PAINT GREEN (-3350 1025);
DISPLAY INVISIBLE (-3350 1025);
FORCEPROP 2 LAST CDS_LIB standard
J 0
(-3375 1125);
DISPLAY INVISIBLE (-3375 1125);
FORCEPROP 2 LAST PATH I87
J 0
(-3625 1175);
DISPLAY 1.021277 (-3625 1175);
DISPLAY INVISIBLE (-3625 1175);
FORCEADD OFFPAGE..2
R 2
(-3375 1275);
FORCEPROP 2 LAST $XR0 146 
J 0
(-3660 1275);
DISPLAY 0.638298 (-3660 1275);
PAINT MONO (-3660 1275);
FORCEPROP 2 LAST CDS_LIB standard
J 0
(-3375 1275);
DISPLAY INVISIBLE (-3375 1275);
FORCEPROP 1 LAST COMMENT_BODY TRUE
J 2
(-3330 1180);
DISPLAY 0.872340 (-3330 1180);
PAINT GREEN (-3330 1180);
DISPLAY INVISIBLE (-3330 1180);
FORCEPROP 1 LAST OFFPAGE TRUE
J 2
(-3700 1150);
DISPLAY 0.872340 (-3700 1150);
PAINT AQUA (-3700 1150);
DISPLAY INVISIBLE (-3700 1150);
FORCEPROP 2 LAST PATH I88
J 0
(-3625 1325);
DISPLAY 1.021277 (-3625 1325);
DISPLAY INVISIBLE (-3625 1325);
FORCEADD OFFPAGE..2
R 2
(-3375 -325);
FORCEPROP 2 LAST $XR0 146 
J 0
(-3660 -325);
DISPLAY 0.638298 (-3660 -325);
PAINT MONO (-3660 -325);
FORCEPROP 2 LAST CDS_LIB standard
J 0
(-3375 -325);
DISPLAY INVISIBLE (-3375 -325);
FORCEPROP 1 LAST COMMENT_BODY TRUE
J 2
(-3330 -420);
DISPLAY 0.872340 (-3330 -420);
PAINT GREEN (-3330 -420);
DISPLAY INVISIBLE (-3330 -420);
FORCEPROP 1 LAST OFFPAGE TRUE
J 2
(-3700 -450);
DISPLAY 0.872340 (-3700 -450);
PAINT AQUA (-3700 -450);
DISPLAY INVISIBLE (-3700 -450);
FORCEPROP 2 LAST PATH I89
J 0
(-3625 -275);
DISPLAY 1.021277 (-3625 -275);
DISPLAY INVISIBLE (-3625 -275);
FORCEADD OFFPAGE..2
R 2
(1400 1200);
FORCEPROP 2 LAST $XR0 146 
J 0
(1145 1200);
DISPLAY 0.638298 (1145 1200);
PAINT MONO (1145 1200);
FORCEPROP 2 LAST CDS_LIB standard
J 0
(1400 1200);
DISPLAY INVISIBLE (1400 1200);
FORCEPROP 1 LAST COMMENT_BODY TRUE
J 2
(1445 1105);
DISPLAY 0.872340 (1445 1105);
PAINT GREEN (1445 1105);
DISPLAY INVISIBLE (1445 1105);
FORCEPROP 1 LAST OFFPAGE TRUE
J 2
(1075 1075);
DISPLAY 0.872340 (1075 1075);
PAINT AQUA (1075 1075);
DISPLAY INVISIBLE (1075 1075);
FORCEPROP 2 LAST PATH I90
J 0
(1150 1250);
DISPLAY 1.021277 (1150 1250);
DISPLAY INVISIBLE (1150 1250);
FORCEADD QUANTA_TITLE_BLOCK_C..1
(4700 -3350);
FORCEPROP 0 LAST CDS_CON_LAST_MODIFIED Fri Aug 25 14:02:01 2023
J 0
(2815 -3335);
PAINT MONO (2815 -3335);
DISPLAY INVISIBLE (2815 -3335);
FORCEPROP 2 LAST CUSTOM_TXT_CDS <XR_PAGE_TITLE>
J 0
(-3190 1900);
DISPLAY 0.638298 (-3190 1900);
PAINT PINK (-3190 1900);
DISPLAY INVISIBLE (-3190 1900);
FORCEPROP 2 LAST CUSTOM_TXT_CDS <CON_PAGE_NUM> OF <CON_TOTAL_PAGES>
J 0
(4225 -3350);
DISPLAY 0.978723 (4225 -3350);
FORCEPROP 2 LAST CUSTOM_TXT_CDS <CON_LAST_MODIFIED>
J 0
(2850 -3325);
DISPLAY 0.978723 (2850 -3325);
FORCEPROP 2 LAST CUSTOM_TXT_CDS <Q_NUMBER>
J 0
(3297 -3247);
DISPLAY 1.212766 (3297 -3247);
FORCEPROP 2 LAST CUSTOM_TXT_CDS <Q_REV>
J 0
(4516 -3247);
DISPLAY 1.212766 (4516 -3247);
FORCEPROP 2 LAST CUSTOM_TXT_CDS <NAME_2>
J 0
(1525 -3300);
FORCEPROP 2 LAST CUSTOM_TXT_CDS <NAME_1>
J 0
(1525 -3175);
FORCEPROP 2 LAST CUSTOM_TXT_CDS <Q_PROJ>
J 0
(2318 -3248);
DISPLAY 1.212766 (2318 -3248);
FORCEPROP 1 LAST Q_TITLE PCIE - CPU1_EXAMAX_P2/P3_X16
J 0
(-4575 -3300);
DISPLAY 1.957447 (-4575 -3300);
PAINT GREEN (-4575 -3300);
FORCEPROP 1 LAST Q_DEPT 
J 1
(937 -3301);
DISPLAY 1.957447 (937 -3301);
PAINT GREEN (937 -3301);
FORCEPROP 2 LAST CDS_XR_PAGE_TITLE CR-140 : @S9S_MB_2U_LIB.S9S_MB_2U(SCH_1):PAGE140
J 0
(-3190 1900);
DISPLAY 0.638298 (-3190 1900);
PAINT PINK (-3190 1900);
DISPLAY INVISIBLE (-3190 1900);
FORCEPROP 1 LAST CDS_LMAN_SYM_OUTLINE -9475,6775,100,-125
J 0
(4700 -3350);
DISPLAY 0.468085 (4700 -3350);
PAINT GREEN (4700 -3350);
DISPLAY INVISIBLE (4700 -3350);
FORCEPROP 2 LAST CDS_LIB pure_quanta
J 0
(4700 -3350);
PAINT MONO (4700 -3350);
DISPLAY INVISIBLE (4700 -3350);
FORCEPROP 1 LAST COMMENT_BODY TRUE
J 0
(4712 -3363);
DISPLAY 0.978723 (4712 -3363);
PAINT GREEN (4712 -3363);
DISPLAY INVISIBLE (4712 -3363);
FORCEPROP 2 LAST PAGE_BORDER TRUE
J 0
(-3190 1900);
DISPLAY 0.638298 (-3190 1900);
PAINT PINK (-3190 1900);
DISPLAY INVISIBLE (-3190 1900);
WIRE 16 -1 (2450 -1200)(2450 -1550);
WIRE 16 -1 (2450 -1050)(2450 -1200);
WIRE 16 -1 (2675 -1200)(2450 -1200);
WIRE 16 -1 (-2275 -1125)(-2275 -1425);
WIRE 16 -1 (-2275 -975)(-2275 -1125);
WIRE 16 -1 (-2100 -1125)(-2275 -1125);
WIRE 16 -1 (-2100 675)(-3325 675);
FORCEPROP 2 LAST SIG_NAME P5E_CPU1_PE3_TX_C_DP<1>
J 0
(-3160 685);
DISPLAY 0.638298 (-3160 685);
WIRE 16 -1 (-2100 825)(-3325 825);
FORCEPROP 2 LAST SIG_NAME P5E_CPU1_PE2_RX_DN<1>
J 0
(-3160 835);
DISPLAY 0.638298 (-3160 835);
WIRE 16 -1 (-2100 875)(-3325 875);
FORCEPROP 2 LAST SIG_NAME P5E_CPU1_PE2_RX_DP<1>
J 0
(-3160 885);
DISPLAY 0.638298 (-3160 885);
WIRE 16 -1 (-2100 975)(-3325 975);
FORCEPROP 2 LAST SIG_NAME P5E_CPU1_PE3_RX_DP<1>
J 0
(-3160 985);
DISPLAY 0.638298 (-3160 985);
WIRE 16 -1 (-2100 1025)(-3325 1025);
FORCEPROP 2 LAST SIG_NAME P5E_CPU1_PE3_RX_DN<1>
J 0
(-3160 1035);
DISPLAY 0.638298 (-3160 1035);
WIRE 16 -1 (-2100 -975)(-2275 -975);
WIRE 16 -1 (-2275 -825)(-2275 -975);
WIRE 16 -1 (-2100 -825)(-2275 -825);
WIRE 16 -1 (-2275 -825)(-2275 -675);
WIRE 16 -1 (-2100 -675)(-2275 -675);
WIRE 16 -1 (-2275 -675)(-2275 -525);
WIRE 16 -1 (-2100 -525)(-2275 -525);
WIRE 16 -1 (-2275 -275)(-2275 -525);
WIRE 16 -1 (-2100 -275)(-2275 -275);
WIRE 16 -1 (-2275 -125)(-2275 -275);
WIRE 16 -1 (-2100 -125)(-2275 -125);
WIRE 16 -1 (-2275 25)(-2275 -125);
WIRE 16 -1 (-2100 25)(-2275 25);
WIRE 16 -1 (-2275 175)(-2275 25);
WIRE 16 -1 (-2100 175)(-2275 175);
WIRE 16 -1 (-2275 325)(-2275 175);
WIRE 16 -1 (-2100 325)(-2275 325);
WIRE 16 -1 (-2275 475)(-2275 325);
WIRE 16 -1 (-2100 475)(-2275 475);
WIRE 16 -1 (-2275 625)(-2275 475);
WIRE 16 -1 (-2100 625)(-2275 625);
WIRE 16 -1 (-2275 775)(-2275 625);
WIRE 16 -1 (-2100 775)(-2275 775);
WIRE 16 -1 (-2275 925)(-2275 775);
WIRE 16 -1 (-2100 925)(-2275 925);
WIRE 16 -1 (-2275 1075)(-2275 925);
WIRE 16 -1 (-2100 1075)(-2275 1075);
WIRE 16 -1 (-2275 1325)(-2275 1075);
WIRE 16 -1 (-2100 1325)(-2275 1325);
WIRE 16 -1 (-2275 1475)(-2275 1325);
WIRE 16 -1 (-2100 1475)(-2275 1475);
WIRE 16 -1 (-2275 1625)(-2275 1475);
WIRE 16 -1 (-2100 1625)(-2275 1625);
WIRE 16 -1 (-2275 1775)(-2275 1625);
WIRE 16 -1 (-2100 1775)(-2275 1775);
WIRE 16 -1 (-2275 1925)(-2275 1775);
WIRE 16 -1 (-2100 1925)(-2275 1925);
WIRE 16 -1 (-2100 1125)(-3325 1125);
FORCEPROP 2 LAST SIG_NAME SMB_BMC_SWB_BUF_SDA
J 0
(-3160 1135);
DISPLAY 0.638298 (-3160 1135);
WIRE 16 -1 (-2100 1275)(-3325 1275);
FORCEPROP 2 LAST SIG_NAME PRSNT_CABLE_GPU_B3_N
J 0
(-3160 1285);
DISPLAY 0.638298 (-3160 1285);
WIRE 16 -1 (-2100 1375)(-3325 1375);
FORCEPROP 2 LAST SIG_NAME P5E_CPU1_PE2_TX_C_DN<0>
J 0
(-3160 1385);
DISPLAY 0.638298 (-3160 1385);
WIRE 16 -1 (-2100 725)(-3325 725);
FORCEPROP 2 LAST SIG_NAME P5E_CPU1_PE3_TX_C_DN<1>
J 0
(-3160 735);
DISPLAY 0.638298 (-3160 735);
WIRE 16 -1 (-2100 575)(-3325 575);
FORCEPROP 2 LAST SIG_NAME P5E_CPU1_PE2_TX_C_DP<1>
J 0
(-3160 585);
DISPLAY 0.638298 (-3160 585);
WIRE 16 -1 (-2100 525)(-3325 525);
FORCEPROP 2 LAST SIG_NAME P5E_CPU1_PE2_TX_C_DN<1>
J 0
(-3160 535);
DISPLAY 0.638298 (-3160 535);
WIRE 16 -1 (-2100 275)(-3325 275);
FORCEPROP 2 LAST SIG_NAME P5E_CPU1_PE3_RX_DN<2>
J 0
(-3160 285);
DISPLAY 0.638298 (-3160 285);
WIRE 16 -1 (-2100 225)(-3325 225);
FORCEPROP 2 LAST SIG_NAME P5E_CPU1_PE3_RX_DP<2>
J 0
(-3160 235);
DISPLAY 0.638298 (-3160 235);
WIRE 16 -1 (-2100 125)(-3325 125);
FORCEPROP 2 LAST SIG_NAME P5E_CPU1_PE2_RX_DP<2>
J 0
(-3160 135);
DISPLAY 0.638298 (-3160 135);
WIRE 16 -1 (-2100 75)(-3325 75);
FORCEPROP 2 LAST SIG_NAME P5E_CPU1_PE2_RX_DN<2>
J 0
(-3160 85);
DISPLAY 0.638298 (-3160 85);
WIRE 16 -1 (-2100 -25)(-3325 -25);
FORCEPROP 2 LAST SIG_NAME P5E_CPU1_PE3_TX_C_DN<2>
J 0
(-3160 -15);
DISPLAY 0.638298 (-3160 -15);
WIRE 16 -1 (-2100 -75)(-3325 -75);
FORCEPROP 2 LAST SIG_NAME P5E_CPU1_PE3_TX_C_DP<2>
J 0
(-3160 -65);
DISPLAY 0.638298 (-3160 -65);
WIRE 16 -1 (-2100 -225)(-3325 -225);
FORCEPROP 2 LAST SIG_NAME P5E_CPU1_PE2_TX_C_DN<2>
J 0
(-3160 -215);
DISPLAY 0.638298 (-3160 -215);
WIRE 16 -1 (-2100 -475)(-3325 -475);
FORCEPROP 2 LAST SIG_NAME SMB_BMC_SWB_BUF_SCL
J 0
(-3160 -465);
DISPLAY 0.638298 (-3160 -465);
WIRE 16 -1 (2675 600)(1425 600);
FORCEPROP 2 LAST SIG_NAME P5E_CPU1_PE3_TX_C_DP<5>
J 0
(1590 610);
DISPLAY 0.638298 (1590 610);
WIRE 16 -1 (2675 750)(1425 750);
FORCEPROP 2 LAST SIG_NAME P5E_CPU1_PE2_RX_DN<5>
J 0
(1590 760);
DISPLAY 0.638298 (1590 760);
WIRE 16 -1 (2675 900)(1425 900);
FORCEPROP 2 LAST SIG_NAME P5E_CPU1_PE3_RX_DN<5>
J 0
(1590 910);
DISPLAY 0.638298 (1590 910);
WIRE 16 -1 (2675 950)(1425 950);
FORCEPROP 2 LAST SIG_NAME P5E_CPU1_PE3_RX_DP<5>
J 0
(1590 960);
DISPLAY 0.638298 (1590 960);
WIRE 16 -1 (2675 1050)(1425 1050);
FORCEPROP 2 LAST SIG_NAME BIC_MONITER
J 0
(1590 1060);
DISPLAY 0.638298 (1590 1060);
WIRE 16 -1 (2675 1200)(1450 1200);
FORCEPROP 2 LAST SIG_NAME GPU_3V3IO_RSVD0_FFU
J 0
(1590 1210);
DISPLAY 0.638298 (1590 1210);
WIRE 16 -1 (-2100 -325)(-3325 -325);
FORCEPROP 2 LAST SIG_NAME GPU_3V3IO_RSVD1_FFU
J 0
(-3160 -315);
DISPLAY 0.638298 (-3160 -315);
WIRE 16 -1 (-2100 -175)(-3325 -175);
FORCEPROP 2 LAST SIG_NAME P5E_CPU1_PE2_TX_C_DP<2>
J 0
(-3160 -165);
DISPLAY 0.638298 (-3160 -165);
WIRE 16 -1 (-2100 1875)(-3325 1875);
FORCEPROP 2 LAST SIG_NAME P5E_CPU1_PE3_RX_DP<0>
J 0
(-3160 1885);
DISPLAY 0.638298 (-3160 1885);
WIRE 16 -1 (-2100 1525)(-3325 1525);
FORCEPROP 2 LAST SIG_NAME P5E_CPU1_PE3_TX_C_DN<0>
J 0
(-3160 1535);
DISPLAY 0.638298 (-3160 1535);
WIRE 16 -1 (-2100 1725)(-3325 1725);
FORCEPROP 2 LAST SIG_NAME P5E_CPU1_PE2_RX_DP<0>
J 0
(-3160 1735);
DISPLAY 0.638298 (-3160 1735);
WIRE 16 -1 (-2100 1675)(-3325 1675);
FORCEPROP 2 LAST SIG_NAME P5E_CPU1_PE2_RX_DN<0>
J 0
(-3160 1685);
DISPLAY 0.638298 (-3160 1685);
WIRE 16 -1 (-2100 1425)(-3325 1425);
FORCEPROP 2 LAST SIG_NAME P5E_CPU1_PE2_TX_C_DP<0>
J 0
(-3160 1435);
DISPLAY 0.638298 (-3160 1435);
WIRE 16 -1 (-2100 1575)(-3325 1575);
FORCEPROP 2 LAST SIG_NAME P5E_CPU1_PE3_TX_C_DP<0>
J 0
(-3160 1585);
DISPLAY 0.638298 (-3160 1585);
WIRE 16 -1 (-2100 1825)(-3325 1825);
FORCEPROP 2 LAST SIG_NAME P5E_CPU1_PE3_RX_DN<0>
J 0
(-3160 1835);
DISPLAY 0.638298 (-3160 1835);
WIRE 16 -1 (-2100 -625)(-3325 -625);
FORCEPROP 2 LAST SIG_NAME P5E_CPU1_PE3_RX_DP<3>
J 0
(-3160 -615);
DISPLAY 0.638298 (-3160 -615);
WIRE 16 -1 (-2100 -725)(-3325 -725);
FORCEPROP 2 LAST SIG_NAME P5E_CPU1_PE2_RX_DP<3>
J 0
(-3160 -715);
DISPLAY 0.638298 (-3160 -715);
WIRE 16 -1 (-2100 -775)(-3325 -775);
FORCEPROP 2 LAST SIG_NAME P5E_CPU1_PE2_RX_DN<3>
J 0
(-3160 -765);
DISPLAY 0.638298 (-3160 -765);
WIRE 16 -1 (-2100 -875)(-3325 -875);
FORCEPROP 2 LAST SIG_NAME P5E_CPU1_PE3_TX_C_DN<3>
J 0
(-3160 -865);
DISPLAY 0.638298 (-3160 -865);
WIRE 16 -1 (-2100 -1075)(-3325 -1075);
FORCEPROP 2 LAST SIG_NAME P5E_CPU1_PE2_TX_C_DN<3>
J 0
(-3160 -1065);
DISPLAY 0.638298 (-3160 -1065);
WIRE 16 -1 (-2100 -925)(-3325 -925);
FORCEPROP 2 LAST SIG_NAME P5E_CPU1_PE3_TX_C_DP<3>
J 0
(-3160 -915);
DISPLAY 0.638298 (-3160 -915);
WIRE 16 -1 (-2100 -575)(-3325 -575);
FORCEPROP 2 LAST SIG_NAME P5E_CPU1_PE3_RX_DN<3>
J 0
(-3160 -565);
DISPLAY 0.638298 (-3160 -565);
WIRE 16 -1 (2675 -150)(1450 -150);
FORCEPROP 2 LAST SIG_NAME P5E_CPU1_PE3_TX_C_DP<6>
J 0
(1590 -140);
DISPLAY 0.638298 (1590 -140);
WIRE 16 -1 (2675 -1050)(2450 -1050);
WIRE 16 -1 (2450 -900)(2450 -1050);
WIRE 16 -1 (2675 -900)(2450 -900);
WIRE 16 -1 (2450 -750)(2450 -900);
WIRE 16 -1 (2675 -750)(2450 -750);
WIRE 16 -1 (2450 -600)(2450 -750);
WIRE 16 -1 (2675 -600)(2450 -600);
WIRE 16 -1 (2450 -350)(2450 -600);
WIRE 16 -1 (2675 -350)(2450 -350);
WIRE 16 -1 (2450 -200)(2450 -350);
WIRE 16 -1 (2675 -200)(2450 -200);
WIRE 16 -1 (2450 -50)(2450 -200);
WIRE 16 -1 (2675 -50)(2450 -50);
WIRE 16 -1 (2450 100)(2450 -50);
WIRE 16 -1 (2675 100)(2450 100);
WIRE 16 -1 (2450 250)(2450 100);
WIRE 16 -1 (2675 250)(2450 250);
WIRE 16 -1 (2450 400)(2450 250);
WIRE 16 -1 (2675 400)(2450 400);
WIRE 16 -1 (2450 550)(2450 400);
WIRE 16 -1 (2675 550)(2450 550);
WIRE 16 -1 (2450 700)(2450 550);
WIRE 16 -1 (2675 700)(2450 700);
WIRE 16 -1 (2450 850)(2450 700);
WIRE 16 -1 (2675 850)(2450 850);
WIRE 16 -1 (2450 1000)(2450 850);
WIRE 16 -1 (2675 1000)(2450 1000);
WIRE 16 -1 (2450 1250)(2450 1000);
WIRE 16 -1 (2675 1250)(2450 1250);
WIRE 16 -1 (2450 1400)(2450 1250);
WIRE 16 -1 (2675 1400)(2450 1400);
WIRE 16 -1 (2450 1550)(2450 1400);
WIRE 16 -1 (2675 1550)(2450 1550);
WIRE 16 -1 (2450 1700)(2450 1550);
WIRE 16 -1 (2675 1700)(2450 1700);
WIRE 16 -1 (2450 1850)(2450 1700);
WIRE 16 -1 (2675 1850)(2450 1850);
WIRE 16 -1 (2675 -250)(1450 -250);
FORCEPROP 2 LAST SIG_NAME P5E_CPU1_PE2_TX_C_DP<6>
J 0
(1590 -240);
DISPLAY 0.638298 (1590 -240);
WIRE 16 -1 (2675 -300)(1450 -300);
FORCEPROP 2 LAST SIG_NAME P5E_CPU1_PE2_TX_C_DN<6>
J 0
(1590 -290);
DISPLAY 0.638298 (1590 -290);
WIRE 16 -1 (2675 -400)(1450 -400);
FORCEPROP 2 LAST SIG_NAME GPU_FPGA_EROT_FATALERR_N
J 0
(1590 -390);
DISPLAY 0.638298 (1590 -390);
WIRE 16 -1 (2675 -100)(1450 -100);
FORCEPROP 2 LAST SIG_NAME P5E_CPU1_PE3_TX_C_DN<6>
J 0
(1590 -90);
DISPLAY 0.638298 (1590 -90);
WIRE 16 -1 (2675 0)(1450 0);
FORCEPROP 2 LAST SIG_NAME P5E_CPU1_PE2_RX_DN<6>
J 0
(1590 10);
DISPLAY 0.638298 (1590 10);
WIRE 16 -1 (2675 50)(1450 50);
FORCEPROP 2 LAST SIG_NAME P5E_CPU1_PE2_RX_DP<6>
J 0
(1590 60);
DISPLAY 0.638298 (1590 60);
WIRE 16 -1 (2675 1500)(1425 1500);
FORCEPROP 2 LAST SIG_NAME P5E_CPU1_PE3_TX_C_DN<4>
J 0
(1590 1510);
DISPLAY 0.638298 (1590 1510);
WIRE 16 -1 (2675 1450)(1425 1450);
FORCEPROP 2 LAST SIG_NAME P5E_CPU1_PE3_TX_C_DP<4>
J 0
(1590 1460);
DISPLAY 0.638298 (1590 1460);
WIRE 16 -1 (2675 1300)(1425 1300);
FORCEPROP 2 LAST SIG_NAME P5E_CPU1_PE2_TX_C_DN<4>
J 0
(1590 1310);
DISPLAY 0.638298 (1590 1310);
WIRE 16 -1 (2675 500)(1425 500);
FORCEPROP 2 LAST SIG_NAME P5E_CPU1_PE2_TX_C_DP<5>
J 0
(1590 510);
DISPLAY 0.638298 (1590 510);
WIRE 16 -1 (2675 450)(1425 450);
FORCEPROP 2 LAST SIG_NAME P5E_CPU1_PE2_TX_C_DN<5>
J 0
(1590 460);
DISPLAY 0.638298 (1590 460);
WIRE 16 -1 (2675 650)(1425 650);
FORCEPROP 2 LAST SIG_NAME P5E_CPU1_PE3_TX_C_DN<5>
J 0
(1590 660);
DISPLAY 0.638298 (1590 660);
WIRE 16 -1 (2675 800)(1425 800);
FORCEPROP 2 LAST SIG_NAME P5E_CPU1_PE2_RX_DP<5>
J 0
(1590 810);
DISPLAY 0.638298 (1590 810);
WIRE 16 -1 (2675 -800)(1450 -800);
FORCEPROP 2 LAST SIG_NAME P5E_CPU1_PE2_RX_DP<7>
J 0
(1590 -790);
DISPLAY 0.638298 (1590 -790);
WIRE 16 -1 (2675 -850)(1450 -850);
FORCEPROP 2 LAST SIG_NAME P5E_CPU1_PE2_RX_DN<7>
J 0
(1590 -840);
DISPLAY 0.638298 (1590 -840);
WIRE 16 -1 (2675 -1000)(1450 -1000);
FORCEPROP 2 LAST SIG_NAME P5E_CPU1_PE3_TX_C_DP<7>
J 0
(1590 -990);
DISPLAY 0.638298 (1590 -990);
WIRE 16 -1 (2675 -1100)(1450 -1100);
FORCEPROP 2 LAST SIG_NAME P5E_CPU1_PE2_TX_C_DP<7>
J 0
(1590 -1090);
DISPLAY 0.638298 (1590 -1090);
WIRE 16 -1 (2675 -1150)(1450 -1150);
FORCEPROP 2 LAST SIG_NAME P5E_CPU1_PE2_TX_C_DN<7>
J 0
(1590 -1140);
DISPLAY 0.638298 (1590 -1140);
WIRE 16 -1 (2675 -700)(1450 -700);
FORCEPROP 2 LAST SIG_NAME P5E_CPU1_PE3_RX_DN<7>
J 0
(1590 -690);
DISPLAY 0.638298 (1590 -690);
WIRE 16 -1 (2675 -550)(1450 -550);
FORCEPROP 2 LAST SIG_NAME BMC_MONITER_BUF
J 0
(1590 -540);
DISPLAY 0.638298 (1590 -540);
WIRE 16 -1 (2675 150)(1450 150);
FORCEPROP 2 LAST SIG_NAME P5E_CPU1_PE3_RX_DN<6>
J 0
(1590 160);
DISPLAY 0.638298 (1590 160);
WIRE 16 -1 (2675 -950)(1450 -950);
FORCEPROP 2 LAST SIG_NAME P5E_CPU1_PE3_TX_C_DN<7>
J 0
(1590 -940);
DISPLAY 0.638298 (1590 -940);
WIRE 16 -1 (2675 -650)(1450 -650);
FORCEPROP 2 LAST SIG_NAME P5E_CPU1_PE3_RX_DP<7>
J 0
(1590 -640);
DISPLAY 0.638298 (1590 -640);
WIRE 16 -1 (2675 200)(1450 200);
FORCEPROP 2 LAST SIG_NAME P5E_CPU1_PE3_RX_DP<6>
J 0
(1590 210);
DISPLAY 0.638298 (1590 210);
WIRE 16 -1 (2675 1350)(1425 1350);
FORCEPROP 2 LAST SIG_NAME P5E_CPU1_PE2_TX_C_DP<4>
J 0
(1590 1360);
DISPLAY 0.638298 (1590 1360);
WIRE 16 -1 (2675 1600)(1425 1600);
FORCEPROP 2 LAST SIG_NAME P5E_CPU1_PE2_RX_DN<4>
J 0
(1590 1610);
DISPLAY 0.638298 (1590 1610);
WIRE 16 -1 (2675 1650)(1425 1650);
FORCEPROP 2 LAST SIG_NAME P5E_CPU1_PE2_RX_DP<4>
J 0
(1590 1660);
DISPLAY 0.638298 (1590 1660);
WIRE 16 -1 (2675 1750)(1425 1750);
FORCEPROP 2 LAST SIG_NAME P5E_CPU1_PE3_RX_DN<4>
J 0
(1590 1760);
DISPLAY 0.638298 (1590 1760);
WIRE 16 -1 (2675 1800)(1425 1800);
FORCEPROP 2 LAST SIG_NAME P5E_CPU1_PE3_RX_DP<4>
J 0
(1590 1810);
DISPLAY 0.638298 (1590 1810);
WIRE 16 -1 (-2100 -1025)(-3325 -1025);
FORCEPROP 2 LAST SIG_NAME P5E_CPU1_PE2_TX_C_DP<3>
J 0
(-3160 -1015);
DISPLAY 0.638298 (-3160 -1015);
DOT 1 (-2275 775);
DOT 1 (-2275 475);
DOT 1 (-2275 175);
DOT 1 (-2275 325);
DOT 1 (-2275 -1125);
DOT 1 (-2275 -975);
DOT 1 (-2275 -675);
DOT 1 (-2275 925);
DOT 1 (-2275 -825);
DOT 1 (-2275 625);
DOT 1 (-2275 -125);
DOT 1 (-2275 1775);
DOT 1 (-2275 1625);
DOT 1 (2450 1700);
DOT 1 (2450 1550);
DOT 1 (2450 1400);
DOT 1 (2450 1250);
DOT 1 (2450 1000);
DOT 1 (2450 850);
DOT 1 (2450 700);
DOT 1 (2450 550);
DOT 1 (2450 100);
DOT 1 (2450 -50);
DOT 1 (2450 -750);
DOT 1 (2450 -600);
DOT 1 (2450 -900);
DOT 1 (2450 -1050);
DOT 1 (2450 -1200);
DOT 1 (-2275 25);
DOT 1 (2450 400);
DOT 1 (-2275 -525);
DOT 1 (-2275 1475);
DOT 1 (-2275 1325);
DOT 1 (2450 250);
DOT 1 (-2275 1075);
DOT 1 (2450 -350);
DOT 1 (2450 -200);
DOT 1 (-2275 -275);
FORCENOTE
DP/DN SWAP
(525 -1125) 0;
DISPLAY LEFT (525 -1125);
DISPLAY 1.021277 (525 -1125);
FORCENOTE
DP/DN SWAP
(-4225 825) 0;
DISPLAY LEFT (-4225 825);
DISPLAY 1.021277 (-4225 825);
FORCENOTE
DP/DN SWAP
(-4225 525) 0;
DISPLAY LEFT (-4225 525);
DISPLAY 1.021277 (-4225 525);
FORCENOTE
DP/DN SWAP
(-4225 100) 0;
DISPLAY LEFT (-4225 100);
DISPLAY 1.021277 (-4225 100);
FORCENOTE
DP/DN SWAP
(-4225 -225) 0;
DISPLAY LEFT (-4225 -225);
DISPLAY 1.021277 (-4225 -225);
FORCENOTE
20210527 MODIFY FOR GT
(-4475 3025) 0;
DISPLAY LEFT (-4475 3025);
DISPLAY 2.510638 (-4475 3025);
PAINT PINK (-4475 3025);
FORCENOTE
DP/DN SWAP
(525 1775) 0;
DISPLAY LEFT (525 1775);
DISPLAY 1.021277 (525 1775);
FORCENOTE
DP/DN SWAP
(525 1600) 0;
DISPLAY LEFT (525 1600);
DISPLAY 1.021277 (525 1600);
FORCENOTE
DP/DN SWAP
(525 1300) 0;
DISPLAY LEFT (525 1300);
DISPLAY 1.021277 (525 1300);
FORCENOTE
DP/DN SWAP
(525 925) 0;
DISPLAY LEFT (525 925);
DISPLAY 1.021277 (525 925);
FORCENOTE
DP/DN SWAP
(525 0) 0;
DISPLAY LEFT (525 0);
DISPLAY 1.021277 (525 0);
FORCENOTE
DP/DN SWAP
(525 -675) 0;
DISPLAY LEFT (525 -675);
DISPLAY 1.021277 (525 -675);
FORCENOTE
DP/DN SWAP
(525 -850) 0;
DISPLAY LEFT (525 -850);
DISPLAY 1.021277 (525 -850);
FORCENOTE
DP/DN SWAP
(-4225 -750) 0;
DISPLAY LEFT (-4225 -750);
DISPLAY 1.021277 (-4225 -750);
FORCENOTE
DP/DN SWAP
(-4225 1700) 0;
DISPLAY LEFT (-4225 1700);
DISPLAY 1.021277 (-4225 1700);
FORCENOTE
DP/DN SWAP
(-4225 1850) 0;
DISPLAY LEFT (-4225 1850);
DISPLAY 1.021277 (-4225 1850);
FORCENOTE
DP/DN SWAP
(-4225 -1075) 0;
DISPLAY LEFT (-4225 -1075);
DISPLAY 1.021277 (-4225 -1075);
FORCENOTE
DP/DN SWAP
(-4200 1375) 0;
DISPLAY LEFT (-4200 1375);
DISPLAY 1.021277 (-4200 1375);
FORCENOTE
DP/DN SWAP
(525 450) 0;
DISPLAY LEFT (525 450);
DISPLAY 1.021277 (525 450);
FORCENOTE
DP/DN SWAP
(525 150) 0;
DISPLAY LEFT (525 150);
DISPLAY 1.021277 (525 150);
FORCENOTE
DP/DN SWAP
(525 750) 0;
DISPLAY LEFT (525 750);
DISPLAY 1.021277 (525 750);
FORCENOTE
DP/DN SWAP
(525 -275) 0;
DISPLAY LEFT (525 -275);
DISPLAY 1.021277 (525 -275);
QUIT
